G04 ================== begin FILE IDENTIFICATION RECORD ==================*
G04 Layout Name:  9048_F0T_Management_Board_D_brd_V04_1213_1625.brd*
G04 Film Name:    bot*
G04 File Format:  Gerber RS274X*
G04 File Origin:  Cadence Allegro 17.2-S081*
G04 Origin Date:  Tue Dec 13 16:31:10 2022*
G04 *
G04 Layer:  DRAWING FORMAT/TITLE_BLOCK_A*
G04 Layer:  DRAWING FORMAT/TITLE_BLOCK*
G04 Layer:  VIA CLASS/BOTTOM*
G04 Layer:  PIN/BOTTOM*
G04 Layer:  MANUFACTURING/PHOTOPLOT_OUTLINE*
G04 Layer:  ETCH/BOTTOM*
G04 Layer:  DRAWING FORMAT/TITLE_DATA_BOT*
G04 *
G04 Offset:    (0.00 0.00)*
G04 Mirror:    No*
G04 Mode:      Positive*
G04 Rotation:  0*
G04 FullContactRelief:  No*
G04 UndefLineWidth:     6.00*
G04 ================== end FILE IDENTIFICATION RECORD ====================*
%FSLAX25Y25*MOIN*%
%IR0*IPPOS*OFA0.00000B0.00000*MIA0B0*SFA1.00000B1.00000*%
%ADD69R,.115X.036*%
%ADD11C,.02*%
%ADD79C,.041*%
%ADD24C,.061*%
%ADD63C,.044*%
%ADD18C,.026*%
%ADD35C,.018*%
%ADD12C,.036*%
%ADD65C,.028*%
%ADD34C,.048*%
%ADD19C,.039*%
%ADD64C,.067*%
%ADD10C,.085*%
%ADD25R,.061X.061*%
%AMMACRO80*
4,1,8,.078,.0425,
.078,-.0425,
-.078,-.0425,
-.078,.0425,
-.0236,.0425,
-.0236,.0145,
.0236,.0145,
.0236,.0425,
.078,.0425,
0.0*
%
%ADD80MACRO80*%
%ADD66R,.044X.044*%
%ADD83C,.0395*%
%ADD31R,.048X.048*%
%ADD84C,.0785*%
%AMMACRO53*
4,1,28,-.00492,.00566,
-.00659,.00733,
-.00269,.01122,
-.002174,.011659,
-.001588,.011998,
-.000951,.01223,
-.000284,.012348,
.000393,.012348,
.001061,.012231,
.001697,.012,
.002284,.011661,
.002803,.011226,
.00284,.01119,
.01119,.00284,
.011631,.002326,
.011978,.001744,
.012217,.00111,
.012343,.000444,
.012352,-.000233,
.012243,-.000902,
.012019,-.001541,
.011688,-.002132,
.011259,-.002656,
.01122,-.00269,
.00733,-.00659,
.00566,-.00492,
-.00172,-.0123,
-.0123,-.00172,
-.00492,.00566,
0.0*
%
%ADD53MACRO53*%
%AMMACRO29*
4,1,28,-.00748,.00052,
-.00984,.00052,
-.00984,.00603,
-.009782,.006705,
-.009607,.007359,
-.009321,.007974,
-.008933,.008529,
-.008455,.009009,
-.0079,.009398,
-.007286,.009685,
-.006632,.009861,
-.005957,.00992,
-.00591,.00992,
.00591,.00992,
.006585,.009869,
.007242,.009701,
.007859,.009421,
.008418,.009039,
.008903,.008565,
.009297,.008015,
.009591,.007404,
.009773,.006751,
.00984,.006077,
.00984,.00603,
.00984,.00052,
.00748,.00052,
.00748,-.00991,
-.00748,-.00991,
-.00748,.00052,
0.0*
%
%ADD29MACRO29*%
%AMMACRO21*
4,1,28,.00052,.00748,
.00052,.00984,
.00603,.00984,
.006705,.009782,
.007359,.009607,
.007974,.009321,
.008529,.008933,
.009009,.008455,
.009398,.0079,
.009685,.007286,
.009861,.006632,
.00992,.005957,
.00992,.00591,
.00992,-.00591,
.009869,-.006585,
.009701,-.007242,
.009421,-.007859,
.009039,-.008418,
.008565,-.008903,
.008015,-.009297,
.007404,-.009591,
.006751,-.009773,
.006077,-.00984,
.00603,-.00984,
.00052,-.00984,
.00052,-.00748,
-.00991,-.00748,
-.00991,.00748,
.00052,.00748,
0.0*
%
%ADD21MACRO21*%
%AMMACRO47*
4,1,8,.0034,.0082,
-.0034,.0082,
-.0082,.0034,
-.0082,-.00341,
-.00341,-.0082,
.0034,-.0082,
.0082,-.0034,
.0082,.0034,
.0034,.0082,
0.0*
%
%ADD47MACRO47*%
%AMMACRO50*
4,1,8,.0082,-.0034,
.0082,.0034,
.0034,.0082,
-.00341,.0082,
-.0082,.00341,
-.0082,-.0034,
-.0034,-.0082,
.0034,-.0082,
.0082,-.0034,
0.0*
%
%ADD50MACRO50*%
%AMMACRO51*
4,1,28,-.00565,.00493,
-.00732,.0066,
-.01121,.0027,
-.011649,.002185,
-.011989,.001599,
-.012222,.000962,
-.01234,.000295,
-.012342,-.000382,
-.012225,-.001049,
-.011994,-.001686,
-.011657,-.002273,
-.011222,-.002793,
-.01119,-.00283,
-.00283,-.01119,
-.002313,-.011629,
-.00173,-.011974,
-.001096,-.012212,
-.00043,-.012337,
.000247,-.012344,
.000915,-.012234,
.001554,-.012009,
.002145,-.011677,
.002668,-.011247,
.0027,-.01121,
.0066,-.00732,
.00493,-.00565,
.0123,.00173,
.00173,.0123,
-.00565,.00493,
0.0*
%
%ADD51MACRO51*%
%AMMACRO28*
4,1,28,-.00748,-.00051,
-.00984,-.00051,
-.00984,-.00602,
-.009782,-.006695,
-.009607,-.007349,
-.009321,-.007964,
-.008933,-.008519,
-.008455,-.008998,
-.0079,-.009388,
-.007287,-.009675,
-.006632,-.009851,
-.005958,-.00991,
-.00591,-.00991,
.00591,-.00991,
.006585,-.009859,
.007242,-.009691,
.007859,-.009411,
.008418,-.009029,
.008903,-.008555,
.009297,-.008005,
.00959,-.007394,
.009773,-.006742,
.00984,-.006068,
.00984,-.00602,
.00984,-.00051,
.00748,-.00051,
.00748,.00992,
-.00748,.00992,
-.00748,-.00051,
0.0*
%
%ADD28MACRO28*%
%AMMACRO15*
4,1,28,-.00051,.00748,
-.00051,.00984,
-.00602,.00984,
-.006695,.009782,
-.007349,.009607,
-.007964,.009321,
-.008519,.008933,
-.008998,.008455,
-.009388,.0079,
-.009675,.007287,
-.009851,.006632,
-.00991,.005958,
-.00991,.00591,
-.00991,-.00591,
-.009859,-.006585,
-.009691,-.007242,
-.009411,-.007859,
-.009029,-.008418,
-.008555,-.008903,
-.008005,-.009297,
-.007394,-.00959,
-.006742,-.009773,
-.006068,-.00984,
-.00602,-.00984,
-.00051,-.00984,
-.00051,-.00748,
.00992,-.00748,
.00992,.00748,
-.00051,.00748,
0.0*
%
%ADD15MACRO15*%
%ADD82R,.012X.02*%
%ADD78R,.05X.04*%
%ADD72R,.032X.022*%
%ADD70R,.026X.011*%
%ADD23R,.04X.05*%
%ADD68R,.011X.026*%
%ADD54R,.04X.025*%
%ADD62R,.024X.024*%
%ADD55R,.071X.04*%
%ADD73R,.036X.032*%
%ADD61R,.016X.024*%
%ADD59C,.131*%
%ADD57R,.014X.044*%
%ADD22R,.024X.017*%
%ADD77R,.013X.046*%
%ADD76R,.07X.017*%
%ADD74R,.032X.036*%
%ADD60R,.028X.04*%
%ADD58R,.032X.028*%
%AMMACRO40*
21,1,.028,.032,0.0,0.0,45.*%
%ADD40MACRO40*%
%ADD32R,.017X.024*%
%ADD67R,.048X.04*%
%ADD52R,.028X.032*%
%ADD44R,.046X.034*%
%ADD43R,.054X.044*%
%ADD20C,.125*%
%ADD49C,.315*%
%ADD30R,.026X.054*%
%ADD71R,.059X.014*%
%ADD42R,.015X.084*%
%ADD33R,.014X.059*%
%ADD75C,.237*%
%ADD41R,.015X.068*%
%ADD14C,.238*%
%ADD13C,.256*%
%ADD56R,.048X.039*%
%AMMACRO81*
4,1,8,-.078,-.0425,
-.078,.0425,
.078,.0425,
.078,-.0425,
.0236,-.0425,
.0236,-.0145,
-.0236,-.0145,
-.0236,-.0425,
-.078,-.0425,
0.0*
%
%ADD81MACRO81*%
%AMMACRO39*
4,1,28,-.00566,-.00492,
-.00733,-.00659,
-.01122,-.00269,
-.011659,-.002174,
-.011998,-.001588,
-.01223,-.000951,
-.012348,-.000284,
-.012348,.000393,
-.012231,.001061,
-.012,.001697,
-.011661,.002284,
-.011226,.002803,
-.01119,.00284,
-.00284,.01119,
-.002326,.011631,
-.001744,.011978,
-.00111,.012217,
-.000444,.012343,
.000233,.012352,
.000902,.012243,
.001541,.012019,
.002132,.011688,
.002656,.011259,
.00269,.01122,
.00659,.00733,
.00492,.00566,
.0123,-.00172,
.00172,-.0123,
-.00566,-.00492,
0.0*
%
%ADD39MACRO39*%
%AMMACRO37*
4,1,28,.00492,-.00566,
.00659,-.00733,
.00269,-.01122,
.002174,-.011659,
.001588,-.011998,
.000951,-.01223,
.000284,-.012348,
-.000393,-.012348,
-.001061,-.012231,
-.001697,-.012,
-.002284,-.011661,
-.002803,-.011226,
-.00284,-.01119,
-.01119,-.00284,
-.011631,-.002326,
-.011978,-.001744,
-.012217,-.00111,
-.012343,-.000444,
-.012352,.000233,
-.012243,.000902,
-.012019,.001541,
-.011688,.002132,
-.011259,.002656,
-.01122,.00269,
-.00733,.00659,
-.00566,.00492,
.00172,.0123,
.0123,.00172,
.00492,-.00566,
0.0*
%
%ADD37MACRO37*%
%AMMACRO27*
4,1,28,-.00052,-.00748,
-.00052,-.00984,
-.00603,-.00984,
-.006705,-.009782,
-.007359,-.009607,
-.007974,-.009321,
-.008529,-.008933,
-.009009,-.008455,
-.009398,-.0079,
-.009685,-.007286,
-.009861,-.006632,
-.00992,-.005957,
-.00992,-.00591,
-.00992,.00591,
-.009869,.006585,
-.009701,.007242,
-.009421,.007859,
-.009039,.008418,
-.008565,.008903,
-.008015,.009297,
-.007404,.009591,
-.006751,.009773,
-.006077,.00984,
-.00603,.00984,
-.00052,.00984,
-.00052,.00748,
.00991,.00748,
.00991,-.00748,
-.00052,-.00748,
0.0*
%
%ADD27MACRO27*%
%AMMACRO17*
4,1,28,.00748,-.00052,
.00984,-.00052,
.00984,-.00603,
.009782,-.006705,
.009607,-.007359,
.009321,-.007974,
.008933,-.008529,
.008455,-.009009,
.0079,-.009398,
.007286,-.009685,
.006632,-.009861,
.005957,-.00992,
.00591,-.00992,
-.00591,-.00992,
-.006585,-.009869,
-.007242,-.009701,
-.007859,-.009421,
-.008418,-.009039,
-.008903,-.008565,
-.009297,-.008015,
-.009591,-.007404,
-.009773,-.006751,
-.00984,-.006077,
-.00984,-.00603,
-.00984,-.00052,
-.00748,-.00052,
-.00748,.00991,
.00748,.00991,
.00748,-.00052,
0.0*
%
%ADD17MACRO17*%
%AMMACRO46*
4,1,8,-.0034,-.0082,
.0034,-.0082,
.0082,-.0034,
.0082,.00341,
.00341,.0082,
-.0034,.0082,
-.0082,.0034,
-.0082,-.0034,
-.0034,-.0082,
0.0*
%
%ADD46MACRO46*%
%AMMACRO45*
4,1,8,-.0082,.0034,
-.0082,-.0034,
-.0034,-.0082,
.00341,-.0082,
.0082,-.00341,
.0082,.0034,
.0034,.0082,
-.0034,.0082,
-.0082,.0034,
0.0*
%
%ADD45MACRO45*%
%AMMACRO38*
4,1,28,-.00493,-.00565,
-.0066,-.00732,
-.0027,-.01121,
-.002185,-.011649,
-.001599,-.011989,
-.000962,-.012222,
-.000295,-.01234,
.000382,-.012342,
.001049,-.012225,
.001686,-.011994,
.002273,-.011657,
.002793,-.011222,
.00283,-.01119,
.01119,-.00283,
.011629,-.002313,
.011974,-.00173,
.012212,-.001096,
.012337,-.00043,
.012344,.000247,
.012234,.000915,
.012009,.001554,
.011677,.002145,
.011247,.002668,
.01121,.0027,
.00732,.0066,
.00565,.00493,
-.00173,.0123,
-.0123,.00173,
-.00493,-.00565,
0.0*
%
%ADD38MACRO38*%
%AMMACRO36*
4,1,28,.00565,-.00493,
.00732,-.0066,
.01121,-.0027,
.011649,-.002185,
.011989,-.001599,
.012222,-.000962,
.01234,-.000295,
.012342,.000382,
.012225,.001049,
.011994,.001686,
.011657,.002273,
.011222,.002793,
.01119,.00283,
.00283,.01119,
.002313,.011629,
.00173,.011974,
.001096,.012212,
.00043,.012337,
-.000247,.012344,
-.000915,.012234,
-.001554,.012009,
-.002145,.011677,
-.002668,.011247,
-.0027,.01121,
-.0066,.00732,
-.00493,.00565,
-.0123,-.00173,
-.00173,-.0123,
.00565,-.00493,
0.0*
%
%ADD36MACRO36*%
%AMMACRO26*
4,1,28,.00051,-.00748,
.00051,-.00984,
.00602,-.00984,
.006695,-.009782,
.007349,-.009607,
.007964,-.009321,
.008519,-.008933,
.008998,-.008455,
.009388,-.0079,
.009675,-.007287,
.009851,-.006632,
.00991,-.005958,
.00991,-.00591,
.00991,.00591,
.009859,.006585,
.009691,.007242,
.009411,.007859,
.009029,.008418,
.008555,.008903,
.008005,.009297,
.007394,.00959,
.006742,.009773,
.006068,.00984,
.00602,.00984,
.00051,.00984,
.00051,.00748,
-.00992,.00748,
-.00992,-.00748,
.00051,-.00748,
0.0*
%
%ADD26MACRO26*%
%AMMACRO16*
4,1,28,.00748,.00051,
.00984,.00051,
.00984,.00602,
.009782,.006695,
.009607,.007349,
.009321,.007964,
.008933,.008519,
.008455,.008998,
.0079,.009388,
.007287,.009675,
.006632,.009851,
.005958,.00991,
.00591,.00991,
-.00591,.00991,
-.006585,.009859,
-.007242,.009691,
-.007859,.009411,
-.008418,.009029,
-.008903,.008555,
-.009297,.008005,
-.00959,.007394,
-.009773,.006742,
-.00984,.006068,
-.00984,.00602,
-.00984,.00051,
-.00748,.00051,
-.00748,-.00992,
.00748,-.00992,
.00748,.00051,
0.0*
%
%ADD16MACRO16*%
%ADD85C,.01*%
%ADD86C,.012*%
%ADD87C,.013*%
%ADD88C,.014*%
%ADD89C,.015*%
%ADD90C,.016*%
%ADD91C,.004*%
%ADD92C,.005*%
%ADD93C,.006*%
%ADD94C,.0051*%
%ADD95C,.0045*%
%ADD96C,.0046*%
%ADD97C,.0056*%
%ADD99C,.03004*%
%ADD100C,.02604*%
%ADD98C,.03604*%
%ADD101C,.02804*%
G75*
%LPD*%
G75*
G36*
G01X331081Y468024D02*
X332262D01*
X332646Y467640D01*
Y451968D01*
G03X336614Y448000I3969J1D01*
G01X346457D01*
G02X352331Y442126I0J-5874D01*
G01Y336646D01*
X345472D01*
G03X341504Y332678I0J-3968D01*
G01Y322834D01*
G03X345472Y318866I3968J0D01*
G01X352331D01*
Y7874D01*
G02X346457Y2000I-5874J0D01*
G01X7874D01*
G02X2000Y7874I0J5874D01*
G01Y318866D01*
X8858D01*
G03X12827Y322835I0J3969D01*
G01Y332677D01*
G03X8858Y336646I-3969J0D01*
G01X2000D01*
Y442126D01*
G02X7874Y448000I5874J0D01*
G01X17717D01*
G03X21685Y451968I-1J3969D01*
G01Y467365D01*
X22132Y467812D01*
X23372D01*
X23682Y467502D01*
Y451968D01*
G02X17717Y446002I-5966J0D01*
G01X7874D01*
G03X3998Y442126I0J-3876D01*
G01Y338644D01*
X8858D01*
G02X14824Y332677I-1J-5967D01*
G01Y322833D01*
G02X8858Y316868I-5966J1D01*
G01X3998D01*
Y7874D01*
G03X7874Y3998I3876J0D01*
G01X250784D01*
X301600D01*
X346457D01*
G03X350334Y7874I0J3877D01*
G01Y316868D01*
X345472D01*
G02X339506Y322834I0J5967D01*
G01Y332678D01*
G02X345472Y338644I5966J-1D01*
G01X350334D01*
Y442126D01*
G03X346459Y446002I-3876J0D01*
G01X336614D01*
G02X330648Y451968I0J5966D01*
G01Y467591D01*
X331081Y468024D01*
G37*
G36*
G01X32595Y315742D02*
X42857D01*
X42895Y315725D01*
G03X43500Y315598I604J1375D01*
G01X43531D01*
X43616Y315600D01*
X46492Y312724D01*
X48039D01*
X48420Y312343D01*
Y308108D01*
X47647Y307335D01*
X12557D01*
X12533Y307359D01*
X12414D01*
X11142Y306087D01*
Y298178D01*
X12858Y296462D01*
X46181D01*
X49097Y293546D01*
Y257940D01*
X44465Y253308D01*
Y236600D01*
X31645Y223780D01*
Y199307D01*
X21510Y189172D01*
X19524D01*
X19502Y189177D01*
G03X19100Y189222I-400J-1757D01*
G03Y185618I0J-1802D01*
G03X19502Y185663I2J1802D01*
G01X19524Y185668D01*
X22235D01*
G03X23104Y185899I0J1752D01*
G01X24200D01*
X37020Y198719D01*
X45540D01*
X50630Y193630D01*
Y187181D01*
X50628Y187166D01*
G03X50608Y186900I1782J-268D01*
G03X50628Y186634I1802J2D01*
G01X50630Y186619D01*
Y185677D01*
X54307Y182000D01*
Y147307D01*
X49642Y142642D01*
X21293D01*
X19969Y141318D01*
Y136069D01*
X16100Y132200D01*
Y126400D01*
X17353Y125147D01*
X52921D01*
X53268Y124800D01*
Y120526D01*
X52937Y120195D01*
X48221D01*
X47701Y119675D01*
X6678D01*
X5073Y121280D01*
Y314903D01*
X5912Y315742D01*
X9000D01*
X10731Y314011D01*
X30501D01*
G03X32197Y315375I199J1489D01*
G02X32595Y315742I399J-33D01*
G37*
G36*
G01X22712Y140656D02*
X50344D01*
X53180Y137820D01*
Y127557D01*
X52023Y126400D01*
X17516D01*
X17224Y126693D01*
X17102Y126815D01*
Y131785D01*
X19675Y134358D01*
X20248Y134931D01*
X20970Y135654D01*
Y136010D01*
X22061Y137100D01*
Y140005D01*
X22712Y140656D01*
G37*
G36*
G01X50217Y304254D02*
Y300306D01*
X48312Y298401D01*
X12834D01*
X12167Y299068D01*
Y305518D01*
X12850Y306201D01*
X48270D01*
X50217Y304254D01*
G37*
G36*
G01X33608Y392100D02*
G03I-508J0D01*
G37*
G36*
G01X34808Y375000D02*
G03I-508J0D01*
G37*
G36*
G01X38828Y468024D02*
X40009D01*
X40382Y467651D01*
Y451968D01*
G03X44350Y448000I3969J1D01*
G01X45976D01*
X46336Y447640D01*
Y446364D01*
X45974Y446002D01*
X44350D01*
G02X38384Y451968I0J5966D01*
G01Y467580D01*
X38828Y468024D01*
G37*
G36*
G01X60408Y199900D02*
G03I-508J0D01*
G37*
G36*
G01X58980Y290605D02*
G03I-326J0D01*
G37*
G36*
G01X60012Y349193D02*
X60781D01*
X63080Y346894D01*
X64200Y345774D01*
Y345409D01*
X64147Y345352D01*
G03X63750Y344618I1253J-1152D01*
G02X63150Y344378I-388J99D01*
G03X62458Y344577I-692J-1104D01*
G03X61156Y343275I0J-1302D01*
G03X61954Y342075I1301J0D01*
G02X62082Y341423I-155J-369D01*
G01X61229Y340571D01*
G03X60868Y339700I870J-871D01*
G01Y339200D01*
X59700D01*
X58100Y340800D01*
Y344185D01*
G03Y346615I-700J1215D01*
G01Y347281D01*
X60012Y349193D01*
G37*
G36*
G01X62414Y351750D02*
X61310Y350645D01*
Y350080D01*
X63495Y347895D01*
X66895D01*
X67412Y348412D01*
Y350400D01*
X66512Y351300D01*
X64964D01*
X64514Y351750D01*
X62414D01*
G37*
G36*
G01X60206Y387418D02*
X58716Y388908D01*
Y389538D01*
X61900Y392722D01*
Y394800D01*
X64400Y397300D01*
X65100D01*
X66900Y395500D01*
Y393312D01*
X61006Y387418D01*
X60206D01*
G37*
G36*
G01X57900Y390200D02*
X57700D01*
X54600Y393300D01*
Y398000D01*
X56200Y399600D01*
X58300D01*
X59500Y400800D01*
X60100D01*
X62100Y398800D01*
Y398400D01*
X60700Y397000D01*
Y393000D01*
X57900Y390200D01*
G37*
G36*
G01X59605Y433502D02*
G03I-508J0D01*
G37*
G36*
G01X57978Y426544D02*
G03I-508J0D01*
G37*
G36*
G01X52043D02*
G03I-508J0D01*
G37*
G36*
G01X65500Y93000D02*
X66500Y94000D01*
X98000D01*
X99500Y92500D01*
Y83000D01*
X97500Y81000D01*
X67000D01*
X65500Y82500D01*
Y93000D01*
G37*
G36*
G01Y104000D02*
X66500Y105000D01*
X95500D01*
X101000Y99500D01*
Y96500D01*
X100000Y95500D01*
X66000D01*
X65500Y96000D01*
Y104000D01*
G37*
G36*
G01X68076Y153380D02*
X79138D01*
X79437Y153081D01*
Y131819D01*
X78642Y131024D01*
X69174D01*
X68098Y132100D01*
G03X67306Y133409I-1791J-190D01*
G01Y152610D01*
X68076Y153380D01*
G37*
G36*
G01X91686Y351800D02*
X92000D01*
X93000Y350800D01*
Y350502D01*
X92949Y350445D01*
G03X92614Y349574I967J-872D01*
G03X93402Y348378I1302J0D01*
G01X93437Y348363D01*
X94500Y347300D01*
Y342800D01*
X97961Y339339D01*
X97862Y339201D01*
G03X97594Y338368I1164J-834D01*
G01Y336868D01*
G03X98014Y335856I1432J1D01*
G01X100100Y333770D01*
Y330310D01*
X99960Y330266D01*
G03Y326828I540J-1719D01*
G01X100100Y326784D01*
Y319636D01*
X95264Y314800D01*
Y313700D01*
X94145Y312581D01*
X94088Y312569D01*
G03X92898Y311100I312J-1469D01*
G03X93539Y309869I1503J0D01*
G01Y308431D01*
G03Y305969I862J-1231D01*
G01Y303239D01*
X84331Y294032D01*
X70869D01*
X69305Y295595D01*
X69384Y295729D01*
G03X68100Y301149I-3439J2047D01*
G01Y311900D01*
X69000Y312800D01*
X72198D01*
G03X74602I1202J899D01*
G01X77000D01*
X82807Y318607D01*
Y336031D01*
G03X83290Y336919I-907J1069D01*
G01X83299Y336986D01*
X83413Y337100D01*
Y350441D01*
X84772Y351800D01*
X86700D01*
G03X88534I917J923D01*
G01X89849D01*
G03X90766Y351422I917J923D01*
G03X91630Y351750I0J1302D01*
G01X91686Y351800D01*
G37*
G36*
G01X93675Y354003D02*
X93656Y354000D01*
X91026D01*
X91007Y354003D01*
G03X90766Y354026I-244J-1279D01*
G03X90525Y354003I3J-1302D01*
G01X90506Y354000D01*
X87877D01*
X87858Y354003D01*
G03X87617Y354026I-244J-1279D01*
G03X87376Y354003I3J-1302D01*
G01X87357Y354000D01*
X80092D01*
X79392Y354701D01*
G03X79385Y354707I-414J-476D01*
G02X79321Y355201I278J287D01*
G03X79508Y355873I-1114J672D01*
G03X76904I-1302J0D01*
G03X77576Y354734I1301J0D01*
G03X77574Y354693I629J-51D01*
G03X77697Y354319I632J1D01*
G01X77736Y354266D01*
Y354000D01*
X77600D01*
X76900Y353300D01*
Y351600D01*
X75888Y350588D01*
X75753Y350674D01*
G03X75057Y350876I-697J-1100D01*
G01X75056D01*
G03X73916Y350203I0J-1302D01*
G01X73859Y350100D01*
X73103D01*
X73046Y350203D01*
G03X72640Y350650I-1141J-628D01*
G01Y351648D01*
G03X73208Y352724I-735J1076D01*
G03X72640Y353799I-1301J0D01*
G01Y354626D01*
X72284Y354856D01*
X71606D01*
X71000Y355462D01*
Y356246D01*
X71606Y356852D01*
X72284D01*
X72640Y357083D01*
Y357948D01*
G03X73208Y359023I-733J1075D01*
G03X73205Y359109I-1302J-2D01*
G01X73199Y359199D01*
X74000Y360000D01*
X75800D01*
X76700Y359100D01*
X76893D01*
X76908Y358916D01*
G03X79504I1298J107D01*
G01X79519Y359100D01*
X81400D01*
X83500Y357000D01*
X83520D01*
X83554Y356948D01*
X84246D01*
X84280Y357000D01*
X84400D01*
X85859Y358459D01*
G02X86488Y358375I282J-284D01*
G03X87617Y357721I1129J647D01*
G03X88666Y358252I0J1302D01*
G01X89717D01*
G03X90766Y357721I1049J771D01*
G03X92068Y359023I0J1302D01*
G01Y359024D01*
G03X92037Y359306I-1302J0D01*
G01X92013Y359413D01*
X92700Y360100D01*
X94800D01*
X95150Y359750D01*
Y359150D01*
X98000Y356300D01*
Y355200D01*
X96800Y354000D01*
X94176D01*
X94157Y354003D01*
G03X93916Y354026I-244J-1279D01*
G03X93675Y354003I3J-1302D01*
G37*
G36*
G01X89690Y374000D02*
G03X90200Y373560I1077J732D01*
G01Y373000D01*
X88764Y371564D01*
Y369088D01*
X88434Y368874D01*
Y368182D01*
X88764Y367968D01*
Y364900D01*
X88164Y364300D01*
X84439D01*
X84210Y364652D01*
X83518D01*
X83290Y364300D01*
X81174D01*
Y364374D01*
X80430Y365118D01*
Y365796D01*
X80198Y366152D01*
X79209D01*
G03X78206Y366624I-1003J-830D01*
G03X77162Y366100I0J-1302D01*
G01X76200D01*
X75800Y366500D01*
Y367000D01*
X72763Y370037D01*
G02X72778Y370617I283J283D01*
G03X73208Y371584I-872J967D01*
G03X72640Y372660I-1303J0D01*
G01Y373657D01*
G03X73044Y374100I-734J1075D01*
G01X73918D01*
G03X76194I1138J633D01*
G01X77068D01*
G03X79344I1138J633D01*
G01X80217D01*
G03X81355Y373431I1138J633D01*
G03X82431Y374000I0J1302D01*
G01X83257D01*
X83322Y374100D01*
X85650D01*
X85715Y374000D01*
X86541D01*
G03X88693I1076J733D01*
G01X89690D01*
G37*
G36*
G01X71494Y381900D02*
X72200D01*
X72600Y381500D01*
Y380463D01*
X72160Y380024D01*
Y379579D01*
G02X71795Y379180I-400J-1D01*
G03X70604Y377883I111J-1297D01*
G03X71134Y376834I1303J0D01*
G01Y375782D01*
G03Y373684I773J-1049D01*
G01Y372633D01*
G03X70719Y372118I773J-1048D01*
G01X70665Y372000D01*
X69998D01*
X69944Y372118D01*
G03X68757Y372886I-1187J-533D01*
G03X67944Y372601I0J-1302D01*
G01X67805Y372490D01*
X66648Y373647D01*
G03X66641Y373653I-414J-476D01*
G02X66625Y373921I140J143D01*
G03X66909Y374733I-1019J812D01*
G03X65607Y376035I-1302J0D01*
G03X64694Y375661I0J-1301D01*
G02X64130Y375663I-281J285D01*
G01X63000Y376793D01*
Y379600D01*
X63856Y380456D01*
G02X64484Y380375I283J-283D01*
G03X65607Y379731I1123J657D01*
G03X66909Y381033I0J1302D01*
G03X66825Y381493I-1302J0D01*
G01X66779Y381614D01*
X67012Y381847D01*
X67464Y381395D01*
X67443Y381290D01*
G03X67417Y381033I1276J-259D01*
G03X68719Y379731I1302J0D01*
G03X69781Y380280I0J1302D01*
G01X70679D01*
X70910Y380641D01*
Y381315D01*
X71494Y381900D01*
G37*
G36*
G01X66805Y433002D02*
G03I-508J0D01*
G37*
G36*
G01X77278Y426543D02*
G03I-508J0D01*
G37*
G36*
G01X71543D02*
G03I-508J0D01*
G37*
G36*
G01X82308Y188500D02*
G03I-508J0D01*
G37*
G36*
G01X89180Y363900D02*
X93700D01*
X95500Y362100D01*
X97400D01*
X97984Y361515D01*
Y358800D01*
X96916D01*
X96152Y359565D01*
Y360165D01*
X95215Y361102D01*
X92285D01*
X91368Y360185D01*
X91246Y360233D01*
G03X90766Y360325I-481J-1210D01*
G03X90037Y360102I0J-1303D01*
G01X88346D01*
G03X86888I-729J-1080D01*
G01X86085D01*
X85784Y359800D01*
X85700D01*
X84352Y358452D01*
X83553D01*
X83551Y358449D01*
X82200Y359800D01*
X82116D01*
X81815Y360102D01*
X80798D01*
X80300Y360600D01*
Y362404D01*
X81195Y363298D01*
X83422D01*
X83518Y363148D01*
X84211D01*
X84307Y363298D01*
X88579D01*
X89180Y363900D01*
G37*
G36*
G01X91216Y372600D02*
X94500D01*
X94998Y372101D01*
Y367385D01*
X96785Y365598D01*
X97402D01*
X97984Y365015D01*
Y363102D01*
X96098D01*
X94900Y364300D01*
X94716D01*
X94115Y364902D01*
X89766D01*
Y368072D01*
X89938Y368182D01*
Y368875D01*
X89766Y368985D01*
Y371149D01*
X91216Y372600D01*
G37*
G36*
G01X91875Y383500D02*
X92800D01*
X92819Y383481D01*
G03X93182Y383106I1098J700D01*
G01Y382109D01*
G03X92614Y381033I735J-1076D01*
G03X93916Y379731I1302J0D01*
G03X94917Y380200I0J1303D01*
G01X95158D01*
X96711Y381753D01*
X97411D01*
X98232Y380932D01*
Y378660D01*
X98212Y378646D01*
Y377954D01*
X98232Y377940D01*
Y376868D01*
X99072Y376028D01*
Y370428D01*
X100200Y369300D01*
Y367000D01*
X99800Y366600D01*
X97200D01*
X96742Y367058D01*
X96752Y367154D01*
Y367846D01*
X96396Y368076D01*
X96000D01*
Y370422D01*
X96396D01*
X96752Y370654D01*
Y371346D01*
X96396Y371576D01*
X96000D01*
Y374157D01*
X96038Y374182D01*
Y374874D01*
X96000Y374899D01*
Y375000D01*
X94300Y376700D01*
X92277D01*
G02X91922Y377284I0J400D01*
G03X92068Y377883I-1156J599D01*
G03X91316Y379063I-1302J0D01*
G01X91200Y379117D01*
Y379799D01*
X91316Y379853D01*
G03Y382213I-550J1180D01*
G01X91200Y382267D01*
Y382948D01*
X91316Y383002D01*
G03X91875Y383500I-550J1180D01*
G37*
G36*
G01X86808Y397600D02*
G03I-508J0D01*
G37*
G36*
G01X104872Y62369D02*
G03I-297J0D01*
G37*
G36*
G01X104901Y67581D02*
G03I-326J0D01*
G37*
G36*
G01X105508Y311900D02*
G03I-508J0D01*
G37*
G36*
G01X103834Y348334D02*
X103872Y348349D01*
G03X104446Y348804I-489J1207D01*
G01X105464D01*
G03X106514Y348272I1050J770D01*
G03X107097Y348410I0J1302D01*
G01X107226Y348474D01*
X107750Y347950D01*
Y346000D01*
X106950Y345200D01*
X104854D01*
G02X104504Y345794I0J400D01*
G03X104667Y346425I-1140J631D01*
G03X103888Y347617I-1301J0D01*
G02X103766Y348266I161J366D01*
G01X103834Y348334D01*
G37*
G36*
G01X115400Y408900D02*
X119600D01*
X120500Y408000D01*
Y405877D01*
X119662Y405038D01*
G03X119206Y404244I1238J-1239D01*
G01X119192Y404192D01*
X117600Y402600D01*
Y390281D01*
X117589Y390250D01*
G03X117498Y389700I1611J-549D01*
G03X117589Y389150I1702J-1D01*
G01X117600Y389119D01*
Y383252D01*
G02X117401Y383052I-200J0D01*
G03Y379648I9J-1702D01*
G02X117600Y379448I-1J-200D01*
G01Y378800D01*
X111682Y372882D01*
X111622Y372870D01*
G03X110248Y371200I328J-1670D01*
G03X110352Y370615I1702J1D01*
G01X110364Y370581D01*
Y362644D01*
G03X110058Y361770I1095J-874D01*
G03X111460Y360368I1402J0D01*
G03X112632Y361000I0J1403D01*
G01X113900D01*
X115600Y359300D01*
Y354950D01*
X114410Y353760D01*
X108820D01*
X107274Y355306D01*
X107352Y355439D01*
G03X107476Y355896I-777J456D01*
G01Y356531D01*
X107896Y356951D01*
Y358048D01*
X107123Y358822D01*
X106027D01*
X105406Y358200D01*
X104594D01*
X104326Y358468D01*
Y359524D01*
X104589D01*
Y359523D01*
G03X105486Y360413I7J890D01*
G01Y361466D01*
X105250D01*
Y362510D01*
X102750D01*
Y361466D01*
X102514D01*
Y360413D01*
G03X102522Y360299I890J5D01*
G01X102524Y360287D01*
Y358468D01*
X102457Y358402D01*
X101842D01*
G03X101274Y358200I1J-902D01*
G01X99586D01*
X98986Y358800D01*
Y365186D01*
X99398Y365598D01*
X100215D01*
X101202Y366585D01*
Y369715D01*
X100100Y370816D01*
Y372600D01*
X100300Y372800D01*
X104900D01*
X108500Y376400D01*
Y379200D01*
X113400Y384100D01*
Y398600D01*
X110900Y401100D01*
X106100D01*
X103800Y398800D01*
X101400D01*
X101000Y399200D01*
Y400700D01*
X101700Y401400D01*
X103400D01*
X103490Y401490D01*
X103750D01*
Y401749D01*
X105100Y403100D01*
Y404977D01*
X106523Y406400D01*
X112900D01*
X115400Y408900D01*
G37*
G36*
G01X100398Y382498D02*
X105102D01*
X107600Y380000D01*
Y379716D01*
X107498Y379615D01*
Y376815D01*
X104485Y373802D01*
X100098D01*
X100074Y373826D01*
Y376443D01*
X99600Y376916D01*
Y377880D01*
X99716Y377954D01*
Y378647D01*
X99600Y378721D01*
Y380100D01*
X99234Y380467D01*
Y381325D01*
X99986Y382077D01*
Y382085D01*
X100398Y382498D01*
G37*
G36*
G01X102764Y392800D02*
X103600D01*
X104800Y391600D01*
X106700D01*
X107100Y392000D01*
X107814D01*
X109226Y390588D01*
Y384126D01*
X108600Y383500D01*
X99659D01*
X99242Y383918D01*
Y384596D01*
X99010Y384952D01*
X98412D01*
X97729Y385635D01*
G02X97790Y386250I283J282D01*
G03X98368Y387332I-724J1082D01*
G01Y387550D01*
X98913D01*
Y387348D01*
Y387332D01*
G03X101517I1302J0D01*
G03X100846Y388471I-1302J0D01*
G01Y388882D01*
X101764Y389800D01*
Y391800D01*
X102764Y392800D01*
G37*
G36*
G01X106515Y400098D02*
X109102D01*
X111800Y397400D01*
Y392700D01*
X110400Y391300D01*
X109930D01*
X108229Y393002D01*
X106685D01*
X106285Y392602D01*
X105215D01*
X104700Y393116D01*
Y398284D01*
X106515Y400098D01*
G37*
G36*
G01X95192Y443287D02*
G03I-632J0D01*
G37*
G36*
G01X100857Y443127D02*
G03I-632J0D01*
G37*
G36*
G01X114039Y80339D02*
X118761D01*
X119600Y79500D01*
Y73100D01*
X119000Y72500D01*
X114000D01*
X113200Y73300D01*
Y76626D01*
X113203Y76642D01*
G03X113232Y77000I-2203J359D01*
G03X113203Y77358I-2232J-1D01*
G01X113200Y77374D01*
Y79500D01*
X114039Y80339D01*
G37*
G36*
G01X122000Y78000D02*
X122407D01*
X122459Y77964D01*
G03X123740Y77560I1280J1827D01*
G01X129285D01*
X129522Y77322D01*
G03X131100Y76668I1578J1577D01*
G01X132500D01*
Y71000D01*
X129000Y67500D01*
X125000D01*
X121500Y71000D01*
Y77500D01*
X122000Y78000D01*
G37*
G36*
G01X128200Y151900D02*
X131100D01*
X131400Y151600D01*
Y147555D01*
X131389Y147524D01*
G03X131268Y146800I2111J-725D01*
G03X131389Y146076I2232J1D01*
G01X131400Y146045D01*
Y143100D01*
X131200Y142900D01*
X128600D01*
X126600Y140900D01*
Y136500D01*
X128176Y134924D01*
Y134672D01*
G03X128198Y134401I1752J6D01*
G01X128200Y134386D01*
Y132100D01*
X127300Y131200D01*
X121500D01*
X121222Y131478D01*
Y131580D01*
G03X118990Y133812I-2232J0D01*
G03X116761Y131690I0J-2232D01*
G01X116752Y131500D01*
X114100D01*
X114000Y131600D01*
Y132900D01*
X112500D01*
X111600Y133800D01*
Y138200D01*
X110502Y139298D01*
Y148302D01*
X111700Y149500D01*
X125800D01*
X128200Y151900D01*
G37*
G36*
G01X119400Y162600D02*
X129600D01*
X131700Y160500D01*
Y160101D01*
X131680Y160060D01*
G03X131458Y159090I2010J-970D01*
G01Y158100D01*
G03X131700Y157090I2232J1D01*
G01Y154300D01*
X131000Y153600D01*
X128200D01*
X125400Y150800D01*
X110600D01*
X110200Y151200D01*
Y157300D01*
X111900Y159000D01*
X113500D01*
X114700Y157800D01*
X117000D01*
X118600Y159400D01*
Y161800D01*
X119400Y162600D01*
G37*
G36*
G01X119626Y199695D02*
G03I-566J0D01*
G37*
G36*
G01X111685Y293471D02*
G03I-508J0D01*
G37*
G36*
G01X136100Y124900D02*
X140300D01*
X141300Y123900D01*
X145300D01*
X145458Y123742D01*
Y123725D01*
X146000Y123184D01*
Y121800D01*
X145200Y121000D01*
X142309D01*
X142258Y121124D01*
G03X139480I-1389J-574D01*
G01X139429Y121000D01*
X136500D01*
X135800Y121700D01*
Y124600D01*
X136100Y124900D01*
G37*
G36*
G01X141441Y137941D02*
X146304D01*
X147341Y136904D01*
Y132679D01*
X145138Y130476D01*
Y127307D01*
X144810Y126979D01*
X136121D01*
X135851Y127249D01*
X135872Y127354D01*
G03X135902Y127652I-1472J299D01*
G03X135812Y128164I-1501J0D01*
G01X135800Y128197D01*
Y132300D01*
X141441Y137941D01*
G37*
G36*
G01X136872Y225272D02*
X146606D01*
X149307Y222571D01*
X150229D01*
X150760Y222040D01*
Y218540D01*
X148571Y216350D01*
Y206609D01*
X147343Y205381D01*
X133590D01*
X133017Y205954D01*
Y220484D01*
X133119Y220531D01*
G03X133145Y220544I-658J1349D01*
G03X133191Y220566I-625J1366D01*
G02X133717Y220419I184J-355D01*
G03X135000Y219698I1283J781D01*
G03Y222702I0J1502D01*
G03X134701Y222672I0J-1502D01*
G01X134486Y222886D01*
X134969Y223369D01*
X135042Y223375D01*
G03X136687Y225020I-151J1796D01*
G01X136693Y225093D01*
X136872Y225272D01*
G37*
G36*
G01X123500Y230900D02*
X124600D01*
X126100Y229400D01*
X128299D01*
X128500Y229200D01*
Y223000D01*
X127800Y222300D01*
X126700D01*
X125359Y223641D01*
G02X125344Y224191I283J283D01*
G03X125728Y225194I-1118J1003D01*
G03X124226Y226696I-1502J0D01*
G03X123574Y226547I0J-1501D01*
G02X123000Y226907I-174J360D01*
G01Y230400D01*
X123500Y230900D01*
G37*
G36*
G01X126563Y239538D02*
X130762D01*
X133356Y236944D01*
X140112D01*
X141092Y235964D01*
Y233992D01*
X140304Y233204D01*
X138925D01*
G03X138000Y233522I-924J-1184D01*
G03X136547Y232400I0J-1502D01*
G01X131300D01*
X129400Y230500D01*
X126500D01*
X126251Y230749D01*
Y239244D01*
G03X126392Y239368I-873J1135D01*
G01X126563Y239538D01*
G37*
G36*
G01X147013Y130586D02*
X149955D01*
X150280Y130261D01*
Y123022D01*
X149288Y122030D01*
X149113D01*
X149109Y122026D01*
X148574D01*
X146460Y124140D01*
Y130033D01*
X147013Y130586D01*
G37*
G36*
G01X152649Y143076D02*
X155517D01*
X156018Y142576D01*
Y138631D01*
X155302Y137916D01*
G03X155035Y137516I871J-871D01*
G01X154555Y136356D01*
X152339D01*
X151951Y136744D01*
Y139233D01*
X151974Y139256D01*
Y142402D01*
X152649Y143076D01*
G37*
G36*
G01X147600Y153900D02*
X151900D01*
X154291Y151509D01*
X158200D01*
X158764Y150945D01*
Y146797D01*
X156378Y144411D01*
G03X156148Y144091I872J-869D01*
G01X152966D01*
X152964Y144090D01*
X152021D01*
X150973Y143042D01*
Y139671D01*
X150644Y139342D01*
G03X149800Y139602I-845J-1242D01*
G03X148775Y139198I0J-1502D01*
G01X143344D01*
X142651Y139891D01*
Y144646D01*
G03X143502Y146000I-652J1354D01*
G03X143492Y146174I-1502J1D01*
G01X143481Y146271D01*
X145480Y148270D01*
Y150316D01*
X146664Y151499D01*
G03X146696Y151532I-1349J1340D01*
G01X146755Y151594D01*
X146904D01*
Y151791D01*
X146934Y151840D01*
G03X147091Y152155I-1616J1002D01*
G01X147107Y152195D01*
X147300Y152388D01*
Y153600D01*
X147600Y153900D01*
G37*
G36*
G01X149790Y206200D02*
X150700Y207110D01*
X153450D01*
X154090Y206470D01*
Y203530D01*
X154898Y202722D01*
G03X156467Y201748I1569J777D01*
G03X158081Y202820I0J1751D01*
G01X158096Y202856D01*
X158760Y203520D01*
X160974D01*
Y201056D01*
X161296D01*
Y199536D01*
X161060Y199300D01*
X159910D01*
X156770Y196160D01*
X151630D01*
X149790Y198000D01*
Y206200D01*
G37*
G36*
G01X155900Y216700D02*
X160100D01*
X160800Y216000D01*
Y214600D01*
X161656Y213744D01*
X163010D01*
X163732Y213022D01*
Y209315D01*
X162529Y208112D01*
X151176D01*
X150453Y208835D01*
Y211604D01*
X150915Y212066D01*
G03X151900Y211698I985J1134D01*
G03X152903Y212082I0J1502D01*
G01X153757D01*
X155419Y213744D01*
Y216219D01*
X155900Y216700D01*
G37*
G36*
G01X151560Y227980D02*
X153494D01*
G03X153572Y227898I1655J1497D01*
G01X154316Y227154D01*
G03X155388Y226559I1577J1578D01*
G01X155443Y226546D01*
X157470Y224519D01*
Y224210D01*
X157464Y224186D01*
G03X157412Y223764I1700J-424D01*
G03X157464Y223342I1752J2D01*
G01X157470Y223318D01*
Y222660D01*
X157914Y222216D01*
Y222180D01*
X157950D01*
X158137Y221993D01*
X160693D01*
X160948Y222248D01*
X161278D01*
G03X162265Y222553I-1J1752D01*
G01X162316Y222588D01*
X163092D01*
X163600Y222080D01*
Y221018D01*
X163326Y220744D01*
X162653D01*
G03X161924Y220599I-1J-1901D01*
G01X161887Y220584D01*
X161636D01*
X160574Y219522D01*
X152778D01*
X152500Y219800D01*
Y222600D01*
X150890Y224210D01*
Y227310D01*
X151560Y227980D01*
G37*
G36*
G01X143600Y241100D02*
X147400D01*
X148200Y240300D01*
X154900D01*
X155841Y239359D01*
X155856Y239329D01*
G03X156881Y238532I1344J671D01*
G01X156939Y238520D01*
X157144Y238314D01*
G03X158015Y237954I870J871D01*
G01X158680D01*
Y237600D01*
X161178D01*
X161923Y236855D01*
X163631D01*
G02X164024Y236380I0J-400D01*
G03X163998Y236100I1476J-278D01*
G03X165500Y234598I1502J0D01*
G03X165705Y234612I0J1502D01*
G02X166160Y234216I55J-396D01*
G01Y231773D01*
X165758Y231371D01*
X163944D01*
X163925Y231375D01*
G03X163500Y231416I-426J-2191D01*
G01X161159D01*
G03X160734Y231375I1J-2232D01*
G01X160715Y231371D01*
X157829D01*
X157400Y231800D01*
Y234800D01*
X157288Y234912D01*
X157277Y234973D01*
G03X155800Y236202I-1477J-273D01*
G03X154773Y235796I0J-1502D01*
G02X154205Y235817I-274J292D01*
G03X153100Y236302I-1105J-1016D01*
G03X151849Y235632I0J-1503D01*
G01X145473D01*
X142300Y238804D01*
Y239800D01*
X143600Y241100D01*
G37*
G36*
G01X163144Y207311D02*
X167200D01*
X168150Y206361D01*
Y203250D01*
X170460Y200940D01*
X170447Y200842D01*
G03X170434Y200655I1389J-190D01*
G03X170492Y200257I1402J1D01*
G01X170500Y200229D01*
Y198726D01*
X170492Y198698D01*
G03X170434Y198300I1344J-399D01*
G03X170492Y197902I1402J1D01*
G01X170500Y197874D01*
Y196900D01*
X169900Y196300D01*
X163000D01*
X162297Y197003D01*
Y206827D01*
X162580Y207110D01*
X162944D01*
X163144Y207311D01*
G37*
G36*
G01X165702Y428688D02*
G03I-508J0D01*
G37*
G36*
G01X182954Y201296D02*
X183361Y200889D01*
X183350Y200794D01*
G03X183343Y200655I1295J-135D01*
G03X183750Y199709I1303J0D01*
G01Y198452D01*
G03X183343Y197506I896J-946D01*
G03X184188Y196287I1302J0D01*
G01X184228Y196272D01*
X185400Y195100D01*
Y193120D01*
X185510Y193010D01*
X185250Y192750D01*
X180750D01*
X177500Y196000D01*
Y196350D01*
X177745D01*
X177786Y196331D01*
G03X178346Y196204I561J1175D01*
G03Y198808I0J1302D01*
G03X178005Y198762I2J-1302D01*
G02X177500Y199148I-105J386D01*
G01Y201200D01*
X178200Y201900D01*
X180018D01*
G02X180365Y201301I0J-400D01*
G03X180193Y200655I1130J-647D01*
G03X182797I1302J0D01*
G03X182759Y200966I-1302J-1D01*
G01X182732Y201075D01*
X182954Y201296D01*
G37*
G36*
G01X173201Y219428D02*
X173422D01*
G02X173699Y218739I0J-400D01*
G03X173298Y217800I901J-940D01*
G03X174600Y216498I1302J0D01*
G03X174966Y216551I-2J1302D01*
G01X175080Y216584D01*
X175385Y216278D01*
G03X175823Y216094I446J448D01*
G03X176711Y215323I882J119D01*
G01Y215324D01*
X177889D01*
Y215323D01*
G03X178489Y215550I6J890D01*
G01X180511D01*
G03X182479I984J854D01*
G01X190782D01*
X191182Y215150D01*
X193927D01*
X194432Y214645D01*
Y211832D01*
X193785Y211186D01*
X192813D01*
G03X192479Y211120I2J-890D01*
G01X192443Y211106D01*
X191776D01*
G03X190944Y211406I-831J-1002D01*
G03X189999Y211000I0J-1303D01*
G01X188739D01*
G03X188506Y211194I-944J-897D01*
G01X188484Y211216D01*
X188473D01*
X188428Y211241D01*
G03X187794Y211406I-634J-1137D01*
G03X187160Y211241I0J-1302D01*
G01X187115Y211216D01*
X185324D01*
X185279Y211241D01*
G03X184645Y211406I-634J-1137D01*
G03X184011Y211241I0J-1302D01*
G01X183966Y211216D01*
X182790D01*
Y212664D01*
X183026D01*
Y212960D01*
X183369D01*
X183415Y212826D01*
G03X184645Y211952I1230J429D01*
G03Y214556I0J1302D01*
G03X183611Y214045I0J-1302D01*
G02X182935Y214111I-317J243D01*
G03X182130Y214608I-799J-393D01*
G01X180952D01*
G03X180327Y214358I-6J-890D01*
G01X179039D01*
X178993Y214384D01*
G03X178346Y214556I-647J-1131D01*
G03Y211952I0J-1302D01*
G03X178819Y212041I0J1301D01*
G01X178854Y212054D01*
X180292D01*
Y210598D01*
X180056D01*
Y209544D01*
G03X180242Y209000I890J0D01*
G02X180225Y208736I-158J-122D01*
G01X179787Y208298D01*
X175000D01*
X174933Y208231D01*
X174880Y208218D01*
G03X173933Y207271I316J-1263D01*
G01X173920Y207218D01*
X173900Y207198D01*
Y207080D01*
X173899Y207071D01*
G03X173894Y206955I1297J-114D01*
G03X173899Y206839I1302J-2D01*
G01X173900Y206830D01*
Y204300D01*
X172600Y203000D01*
X170000D01*
X169300Y203700D01*
Y209509D01*
X170800Y211009D01*
Y213246D01*
X170929Y213294D01*
G03X171902Y214700I-529J1406D01*
G03X170400Y216202I-1502J0D01*
G03X169891Y216113I0J-1502D01*
G02X169356Y216490I-135J377D01*
G01Y218832D01*
X169952Y219428D01*
X171601D01*
G03X172400Y219198I799J1273D01*
G03X173154Y219401I0J1502D01*
G01X173201Y219428D01*
G37*
G36*
G01X168434Y223456D02*
Y234571D01*
G02X168645Y234771I200J0D01*
G03X168716Y234768I87J1228D01*
G01X170990D01*
X171268Y234490D01*
Y233700D01*
G03X171629Y232829I1231J0D01*
G01X172466Y231992D01*
G03X173337Y231632I870J871D01*
G01X174969D01*
G03X176144Y231161I1175J1230D01*
G03X177299Y231613I0J1702D01*
G01X177356Y231666D01*
X177534D01*
X178255Y230945D01*
G02X178060Y230272I-283J-283D01*
G03X177044Y229002I286J-1270D01*
G03X178346Y227700I1302J0D01*
G03X179112Y227949I0J1303D01*
G01X179250Y228050D01*
X180543Y226757D01*
X180443Y226619D01*
G03X180193Y225852I1052J-767D01*
G03X182797I1302J0D01*
G03X182796Y225913I-1302J9D01*
G01X182791Y226001D01*
X182995Y226205D01*
X183341Y225859D01*
X183345Y225783D01*
G03X184576Y224552I1300J69D01*
G01X184652Y224548D01*
X184997Y224203D01*
X184793Y224000D01*
X184705Y224004D01*
G03X184645Y224005I-52J-1301D01*
G03X185947Y222703I0J-1302D01*
G03X185946Y222763I-1302J8D01*
G01X185942Y222851D01*
X186145Y223055D01*
X186490Y222710D01*
X186494Y222634D01*
G03X187794Y221401I1300J69D01*
G03X188391Y221546I0J1301D01*
G01X188434Y221568D01*
X188800D01*
X189432Y222200D01*
X189737D01*
X189793Y222093D01*
G03X190944Y221400I1151J609D01*
G03X191852Y221769I0J1302D01*
G01X191993Y221907D01*
X192300Y221600D01*
Y218976D01*
X192274Y218950D01*
X191058D01*
X190286Y218178D01*
Y216552D01*
X182798D01*
X182761Y216705D01*
G03X180229I-1266J-301D01*
G01X180192Y216552D01*
X179091D01*
X178786Y216857D01*
Y217266D01*
X178550D01*
Y219334D01*
X178786D01*
Y220387D01*
G03X177889Y221277I-890J0D01*
G01Y221276D01*
X177017D01*
X174432Y223862D01*
Y224148D01*
G03X175202Y225400I-633J1252D01*
G03X172398I-1402J0D01*
G03X173168Y224148I1403J0D01*
G01Y223600D01*
G03X173353Y223153I633J0D01*
G01X173824Y222683D01*
G02X173541Y222000I-283J-283D01*
G01X173154D01*
X173110Y222024D01*
G03X172400Y222202I-709J-1324D01*
G03X171648Y222000I0J-1501D01*
G01X169500D01*
X168688Y222812D01*
X168677Y222873D01*
G03X168434Y223456I-1477J-273D01*
G37*
G36*
G01X188278Y261490D02*
X186300D01*
X184837Y262953D01*
G02X184927Y263585I283J282D01*
G03X185702Y264900I-728J1315D01*
G03X182698I-1502J0D01*
G03X182717Y264663I1502J1D01*
G02X182322Y264200I-395J-63D01*
G01X180000D01*
X179600Y264600D01*
Y270770D01*
X178500Y271870D01*
Y275800D01*
X179865Y277165D01*
G03X179934Y277200I-648J1363D01*
G01X182394D01*
Y274360D01*
G03X182123Y273500I1231J-861D01*
G03X183396Y272016I1501J0D01*
G02X183685Y271427I-61J-395D01*
G03X183498Y270702I1315J-726D01*
G01Y270700D01*
G03X186502I1502J0D01*
G03X185229Y272184I-1501J0D01*
G02X184940Y272773I61J395D01*
G03X185127Y273498I-1315J726D01*
G01Y273500D01*
G03X184856Y274360I-1502J-1D01*
G01Y277200D01*
X190263D01*
X190700Y276763D01*
Y276694D01*
X191665Y275728D01*
X195989D01*
X196023Y275763D01*
X198643D01*
X198859Y275547D01*
Y274005D01*
X198564Y273710D01*
X196688D01*
X196673Y273695D01*
X196671D01*
X195380Y272404D01*
X194033D01*
X190114Y268486D01*
X189724D01*
Y268250D01*
X188680D01*
Y265750D01*
X189034D01*
Y264015D01*
X188372Y262419D01*
G03X188278Y261948I1138J-472D01*
G01Y261490D01*
G37*
G36*
G01X174388Y312430D02*
G03I-508J0D01*
G37*
G36*
G01X178902Y327100D02*
X183200D01*
X184200Y326100D01*
Y323100D01*
X184100Y323000D01*
X178000D01*
X177400Y323600D01*
Y325598D01*
X178902Y327100D01*
G37*
G36*
G01X187852Y132425D02*
G03I-492J0D01*
G37*
G36*
G01X192870Y177406D02*
X192539Y177737D01*
Y179250D01*
X192784Y179494D01*
X197818D01*
X198162Y179150D01*
Y178250D01*
X197318Y177406D01*
X192870D01*
G37*
G36*
G01X201727Y173298D02*
X202288D01*
X202510Y173076D01*
Y171146D01*
X203481Y170175D01*
X207111D01*
X207826Y169460D01*
Y167734D01*
X207432Y167340D01*
X206845D01*
X206834Y167341D01*
G03X206692Y167349I-144J-1294D01*
G03X206550Y167341I2J-1302D01*
G01X206539Y167340D01*
X203879D01*
X203200Y168019D01*
X203170D01*
X202726Y168463D01*
G03X201926Y168794I-800J-801D01*
G01X199480D01*
X199363Y168912D01*
Y169671D01*
X199349Y169685D01*
Y169934D01*
X198326Y170957D01*
X196742D01*
X196445Y171254D01*
Y172927D01*
X196814Y173296D01*
X201727D01*
Y173298D01*
G37*
G36*
G01X190398Y176356D02*
X194048D01*
X194550Y175854D01*
Y173792D01*
X194230Y173472D01*
X192465D01*
X191850Y172857D01*
Y171903D01*
X191824Y171876D01*
Y170824D01*
X191416Y170416D01*
X191303Y170449D01*
G03X190944Y170499I-357J-1252D01*
G03X190479Y170413I0J-1302D01*
G01X190445Y170400D01*
X190400D01*
X190362Y170362D01*
X190336Y170348D01*
G03X189793Y169805I608J-1151D01*
G01X189779Y169779D01*
X189500Y169500D01*
X189068D01*
X189021Y169633D01*
G03X187794Y170499I-1227J-436D01*
G03X186725Y169940I0J-1302D01*
G02X186114Y169886I-328J229D01*
G01X185900Y170100D01*
Y171999D01*
X185906Y172024D01*
G03X185947Y172347I-1261J324D01*
G03X185906Y172670I-1302J-1D01*
G01X185900Y172695D01*
Y174700D01*
X186071Y174871D01*
G02X186693Y174802I284J-282D01*
G03X187794Y174194I1101J693D01*
G03X189063Y175203I0J1302D01*
G01X189076Y175259D01*
X189216Y175400D01*
X189442D01*
X190398Y176356D01*
G37*
G36*
G01X199543Y179043D02*
X200974D01*
X201246Y178772D01*
Y176837D01*
X201288Y176795D01*
Y174717D01*
X200971Y174400D01*
X196619D01*
X196174Y174845D01*
Y175983D01*
X196579Y176388D01*
X197739D01*
X199188Y177837D01*
Y178688D01*
X199543Y179043D01*
G37*
G36*
G01X186825Y188369D02*
X188386D01*
X188634Y188121D01*
Y184656D01*
X188650Y184640D01*
Y184624D01*
X190215Y183058D01*
X190230D01*
X190285Y183003D01*
X198091D01*
X198326Y182768D01*
Y180704D01*
X198125Y180504D01*
X192408D01*
X192400Y180496D01*
X192370D01*
X191538Y179666D01*
Y177838D01*
X191200Y177500D01*
X189900D01*
X188903Y176503D01*
G02X188633Y176492I-141J142D01*
G03X187794Y176798I-839J-997D01*
G03X186699Y176200I0J-1302D01*
G01X186400D01*
X185600Y177000D01*
Y177761D01*
G03Y179531I-955J885D01*
G01Y180910D01*
G03Y182680I-955J885D01*
G01Y184060D01*
G03X185947Y184945I-955J885D01*
G03X185860Y185414I-1302J1D01*
G01X185813Y185535D01*
X186678Y186400D01*
Y188222D01*
X186825Y188369D01*
G37*
G36*
G01X196809Y220854D02*
X197908D01*
X198445Y220317D01*
Y218534D01*
X198368Y218458D01*
X197788D01*
Y217878D01*
X197307Y217396D01*
Y212580D01*
X198649Y211238D01*
X201203D01*
X201682Y210759D01*
Y209467D01*
X200908Y208693D01*
X198667D01*
X198276Y208302D01*
Y202244D01*
X198625Y201895D01*
X202235D01*
X202470Y202130D01*
Y204370D01*
X202630Y204530D01*
X208110D01*
X208450Y204190D01*
Y202280D01*
X209080Y201650D01*
X210390D01*
X210620Y201420D01*
Y196806D01*
X210436Y196622D01*
X209098D01*
X208157Y195681D01*
Y192554D01*
X208826Y191885D01*
Y189287D01*
X209850Y188263D01*
X212393D01*
X216706Y192576D01*
Y194755D01*
X216908Y194957D01*
X222233D01*
X222686Y194504D01*
Y193200D01*
X222319Y192833D01*
X220649D01*
X220183Y192367D01*
Y190912D01*
X219457Y190186D01*
X218865D01*
X218863Y190184D01*
X218685D01*
X217415Y188914D01*
X215902D01*
X213424Y186436D01*
Y186229D01*
X213208D01*
X213193Y186231D01*
G03X212991Y186247I-203J-1286D01*
G03Y183643I0J-1302D01*
G01X213016D01*
G02X213424Y183243I8J-400D01*
G01Y182728D01*
X213675Y182477D01*
Y182473D01*
X215321Y180827D01*
X217207D01*
X219312Y182932D01*
X220988D01*
X221285Y182635D01*
Y180359D01*
X220420Y179494D01*
Y177806D01*
X220879Y177347D01*
Y171266D01*
X220731Y171118D01*
X219140D01*
X218681Y171577D01*
Y172467D01*
X216711Y174437D01*
Y177302D01*
X213722Y180291D01*
X210884D01*
X210169Y179576D01*
Y177539D01*
X209991Y177361D01*
X206455D01*
X206075Y176981D01*
X202518D01*
X202247Y177252D01*
Y179770D01*
X201486Y180531D01*
X199903D01*
X199327Y181107D01*
Y182666D01*
X199619Y182958D01*
X201670D01*
X204815Y179812D01*
X207715D01*
X208951Y181048D01*
Y185192D01*
X208955Y185211D01*
G03X208972Y185382I-873J173D01*
G01Y186436D01*
X208951D01*
Y187281D01*
X208279Y187953D01*
X202016D01*
X201903Y188066D01*
X198009D01*
X197913Y188162D01*
X193126D01*
X192688Y188600D01*
Y191645D01*
X193163Y192120D01*
X200528D01*
X201339Y192931D01*
Y196046D01*
X200833Y196552D01*
X193840D01*
X193438Y196954D01*
Y204320D01*
X193832Y204714D01*
X193866D01*
Y204748D01*
X193878Y204760D01*
X194583D01*
X194774Y204950D01*
X194910D01*
Y205086D01*
X195564Y205741D01*
Y208078D01*
X195450Y208192D01*
Y215043D01*
X194342Y216151D01*
X191597D01*
X191287Y216461D01*
Y217763D01*
X191473Y217949D01*
X195496D01*
X196367Y218820D01*
Y220412D01*
X196809Y220854D01*
G37*
G36*
G01X190080Y201600D02*
X192106D01*
X192436Y201270D01*
Y196301D01*
X193195Y195542D01*
X200127D01*
X200335Y195334D01*
Y193382D01*
X200078Y193125D01*
X192739D01*
X191767Y192153D01*
Y192140D01*
X191686Y192060D01*
Y188185D01*
X191767Y188105D01*
Y188103D01*
X192732Y187138D01*
X197514D01*
X197590Y187062D01*
X197592Y187064D01*
X201488D01*
X201601Y186952D01*
X207864D01*
X207950Y186866D01*
Y181528D01*
X207772Y181351D01*
X207304Y180882D01*
X205501D01*
X202323Y184060D01*
X190630D01*
X189651Y185039D01*
Y200940D01*
X189671Y200981D01*
G03X189765Y201244I-1171J567D01*
G01X189778Y201298D01*
X190080Y201600D01*
G37*
G36*
G01X187087Y202140D02*
X188088D01*
X188650Y201578D01*
Y193242D01*
X187071D01*
X186401Y193912D01*
Y201454D01*
X187087Y202140D01*
G37*
G36*
G01X193866Y208378D02*
X194347D01*
X194448Y208276D01*
Y207777D01*
X194562Y207663D01*
Y206306D01*
X194235Y205978D01*
X193260D01*
X192240Y204958D01*
Y203290D01*
X191760Y202810D01*
X190470D01*
X189986Y203294D01*
Y204266D01*
X189952D01*
Y206334D01*
X189986D01*
Y207387D01*
G03X189958Y207605I-890J-4D01*
G01X189952Y207630D01*
Y207758D01*
X190404Y208210D01*
X191865D01*
X192033Y208378D01*
X192296D01*
X192345Y208348D01*
G03X192813Y208214I470J756D01*
G01X193866D01*
Y208378D01*
G37*
G36*
G01X197103Y272709D02*
X200210D01*
X200213Y272706D01*
X206720D01*
X206835Y272590D01*
Y268682D01*
X206035Y267882D01*
X196879D01*
X196182Y268579D01*
Y271788D01*
X197103Y272709D01*
G37*
G36*
G01X194445Y288242D02*
X199054D01*
X199712Y287583D01*
Y285550D01*
X199736Y285527D01*
Y284777D01*
X199720Y284762D01*
Y277764D01*
X199065Y277108D01*
X197614D01*
X197612Y277111D01*
X195955D01*
X195574Y276730D01*
X192080D01*
X191701Y277109D01*
Y278573D01*
X193743Y280615D01*
Y287540D01*
X194445Y288242D01*
G37*
G36*
G01X208208Y59100D02*
G03I-508J0D01*
G37*
G36*
G01X204462Y125500D02*
G03I-492J0D01*
G37*
G36*
G01X211692Y140513D02*
G03I-492J0D01*
G37*
G36*
G01X206842Y176332D02*
X210459D01*
X210711Y176080D01*
Y174792D01*
X209508Y173589D01*
Y171430D01*
X209255Y171177D01*
X203895D01*
X203512Y171561D01*
Y173491D01*
X203420Y173582D01*
Y174461D01*
X202640Y175241D01*
Y175980D01*
X206490D01*
X206842Y176332D01*
G37*
G36*
G01X211456Y179262D02*
X213306D01*
X215668Y176900D01*
Y174047D01*
X216531Y173184D01*
Y171386D01*
X216343Y171198D01*
X214656D01*
X212972Y172882D01*
X212966Y172956D01*
G03X212150Y173772I-888J-72D01*
G01X212076Y173778D01*
X211870Y173984D01*
Y176400D01*
X211263Y177007D01*
Y179069D01*
X211456Y179262D01*
G37*
G36*
G01X206112Y210720D02*
X207415D01*
X207833Y210302D01*
Y208475D01*
X208427Y207881D01*
X210979D01*
X211294Y207566D01*
Y206584D01*
X211298Y206580D01*
Y206578D01*
X213892Y203985D01*
Y199814D01*
X213897Y199809D01*
Y196131D01*
X215188Y194840D01*
X215592D01*
X215704Y194728D01*
Y192992D01*
X211976Y189264D01*
X210265D01*
X209828Y189702D01*
Y192300D01*
X209821Y192306D01*
Y192459D01*
X209172Y193108D01*
Y195256D01*
X209482Y195566D01*
X211178D01*
X211645Y196033D01*
Y201925D01*
X211200Y202370D01*
X211086D01*
X210805Y202652D01*
X209495D01*
X209452Y202695D01*
Y204605D01*
X208525Y205532D01*
X202215D01*
X201934Y205250D01*
X201750D01*
X201480Y204980D01*
Y204796D01*
X201468Y204785D01*
Y202896D01*
X199278D01*
Y207692D01*
X201323D01*
X201512Y207881D01*
X204953D01*
X205445Y208373D01*
Y210053D01*
X206112Y210720D01*
G37*
G36*
G01X213869Y210776D02*
Y208916D01*
X214665Y208120D01*
X217223D01*
X217418Y207925D01*
Y200214D01*
X217117Y199912D01*
X215212D01*
X214893Y200230D01*
Y204400D01*
X212300Y206993D01*
Y208340D01*
X211718Y208922D01*
X209492D01*
Y208926D01*
X208899Y209519D01*
Y210734D01*
X209433Y211268D01*
X213377D01*
X213869Y210776D01*
G37*
G36*
G01X199032Y217705D02*
X204253D01*
X204477Y217481D01*
Y212669D01*
X204034Y212226D01*
X201631D01*
X201618Y212240D01*
X199096D01*
X198308Y213026D01*
Y216981D01*
X199032Y217705D01*
G37*
G36*
G01X212409Y276726D02*
X214910D01*
X215656Y275980D01*
Y274821D01*
X215848Y274629D01*
Y274556D01*
X219771Y270633D01*
Y269364D01*
X219018Y268611D01*
X216146D01*
X215303Y269454D01*
X208748D01*
X208396Y269806D01*
Y272456D01*
X208646Y272706D01*
X211405D01*
X211438Y272739D01*
X211506D01*
X212195Y273428D01*
Y276512D01*
X212409Y276726D01*
G37*
G36*
G01X207720Y284265D02*
Y277155D01*
X208568Y276307D01*
X210601D01*
X211172Y275736D01*
Y273889D01*
X210990Y273707D01*
X200628D01*
X200038Y274297D01*
Y276665D01*
X200722Y277349D01*
Y284347D01*
X200861Y284486D01*
X207498D01*
X207720Y284265D01*
G37*
G36*
G01X207721Y285716D02*
X207553Y285548D01*
X201131D01*
X200714Y285965D01*
Y287998D01*
X198665Y290047D01*
Y292325D01*
X199678Y293338D01*
X202487D01*
X207186Y288639D01*
Y288324D01*
X207721Y287789D01*
Y285716D01*
G37*
G36*
G01X230161Y302065D02*
X238793D01*
X239129Y301729D01*
G03X240000Y301368I871J870D01*
G01X244783D01*
G02X245081Y300702I0J-400D01*
G03X244698Y299700I1119J-1002D01*
G03X246200Y298198I1502J0D01*
G03X247218Y298596I0J1501D01*
G02X247889Y298301I271J-294D01*
G01Y291813D01*
X247428Y291352D01*
X235290D01*
X235106Y291536D01*
G02X235202Y292172I283J283D01*
G03X236002Y293500I-702J1328D01*
G03X234500Y295002I-1502J0D01*
G03X233172Y294202I0J-1502D01*
G02X232536Y294106I-353J187D01*
G01X230940Y295702D01*
X230873D01*
X230630Y295946D01*
X228213D01*
X227970Y295702D01*
X226586D01*
X226577Y295703D01*
G03X226404Y295712I-177J-1743D01*
G01X223646D01*
G03X223473Y295703I4J-1752D01*
G01X223464Y295702D01*
X211414D01*
X210670Y294958D01*
Y292856D01*
X211465Y292061D01*
X213833D01*
X214760Y291134D01*
Y281503D01*
X214440Y281183D01*
X212457D01*
X211808Y280534D01*
Y280156D01*
X211800Y280149D01*
Y277681D01*
X211559Y277439D01*
X209142D01*
X208732Y277849D01*
Y289378D01*
X205720Y292390D01*
Y296733D01*
G02X205905Y296932I200J0D01*
G03X206681Y297289I-95J1228D01*
G01X206693Y297301D01*
G03X207932Y298780I-263J1479D01*
G03X207808Y299377I-1502J-1D01*
G02X207975Y299881I367J158D01*
G03X208722Y301180I-756J1299D01*
G03X208672Y301563I-1502J-1D01*
G02X209059Y302065I387J102D01*
G01X227439D01*
G03X230161I1361J635D01*
G37*
G36*
G01X219522Y115664D02*
X226496D01*
X226694Y115466D01*
G03X227158Y115155I1014J1011D01*
G01X229519Y114177D01*
G03X230067Y114068I548J1323D01*
G01X231423D01*
Y112302D01*
X231260Y112271D01*
G03Y108729I332J-1771D01*
G01X231423Y108698D01*
Y106108D01*
X230522Y105207D01*
X218891D01*
X218148Y105950D01*
X218169Y106054D01*
G03X218202Y106400I-1769J343D01*
G03X218153Y106816I-1802J-1D01*
G01X218148Y106838D01*
Y114290D01*
X219522Y115664D01*
G37*
G36*
G01X221992Y125100D02*
G03I-492J0D01*
G37*
G36*
G01X226384Y174430D02*
X231829D01*
X232430Y173830D01*
X233713D01*
X234017Y173526D01*
X235774D01*
X236100Y173200D01*
Y169200D01*
X238800Y166500D01*
X242100D01*
X242500Y166100D01*
Y164200D01*
X242100Y163800D01*
X239089D01*
G03X237211I-939J-902D01*
G01X235940D01*
G03X234062I-939J-902D01*
G01X232790D01*
G03X230912I-939J-902D01*
G01X230000D01*
X229416Y164384D01*
G02X229464Y164991I282J283D01*
G03X230004Y166047I-763J1056D01*
G03X228702Y167349I-1302J0D01*
G03X227646Y166809I0J-1303D01*
G02X227039Y166761I-324J234D01*
G01X226266Y167534D01*
G02X226314Y168141I282J283D01*
G03X226854Y169197I-763J1056D01*
G03X226056Y170398I-1303J0D01*
G01X225933Y170449D01*
Y173979D01*
X226384Y174430D01*
G37*
G36*
G01X221891Y179540D02*
X223313D01*
X223632Y179222D01*
Y177705D01*
X224044Y177293D01*
Y174508D01*
Y171274D01*
X222045D01*
X221882Y171437D01*
Y174381D01*
Y177795D01*
X221482Y178195D01*
Y179131D01*
X221699Y179348D01*
X221891Y179540D01*
G37*
G36*
G01X222420Y182883D02*
X225809D01*
X226180Y182512D01*
Y181260D01*
X225640Y180720D01*
X222458D01*
X222286Y180892D01*
Y182750D01*
X222420Y182883D01*
G37*
G36*
G01X220797Y186490D02*
X221111Y186804D01*
X223198D01*
X223270Y186732D01*
Y186256D01*
X223670Y185856D01*
X225950D01*
X226411Y185395D01*
Y184469D01*
X225860Y183918D01*
X221184D01*
X220797Y184305D01*
Y186490D01*
G37*
G36*
G01X219027Y189110D02*
X219626D01*
X219808Y188928D01*
Y186917D01*
X219796Y186905D01*
Y184842D01*
X216984Y182030D01*
X215565D01*
X214865Y182730D01*
Y186461D01*
X216317Y187912D01*
X217830D01*
X219027Y189110D01*
G37*
G36*
G01X218058Y218217D02*
X222705D01*
X223650Y217272D01*
Y215042D01*
X223314Y214705D01*
X221924D01*
X221300Y214081D01*
Y213949D01*
X221273Y213903D01*
G03X221100Y213254I1129J-649D01*
G03X221300Y212561I1301J0D01*
G01Y207648D01*
G03Y206262I1101J-693D01*
G01Y205490D01*
X221288Y205457D01*
G03X221233Y205144I835J-308D01*
G01X221234D01*
Y203966D01*
X221233D01*
G03X221288Y203653I890J-5D01*
G01X221300Y203620D01*
Y199799D01*
X222083Y199016D01*
X223244D01*
X223651Y198609D01*
Y197249D01*
X226155Y194745D01*
X229786D01*
X230232Y194299D01*
Y193179D01*
X229591Y192538D01*
X228846D01*
X228836Y192539D01*
G03X228702Y192546I-135J-1295D01*
G03X228568Y192539I1J-1302D01*
G01X228558Y192538D01*
X227964D01*
X227282Y191856D01*
G02X226659Y191929I-283J283D01*
G03X225552Y192546I-1107J-685D01*
G03X224250Y191244I0J-1302D01*
G03X224343Y190760I1302J-1D01*
G02X223972Y190211I-371J-149D01*
G01X223344D01*
X223293Y190247D01*
G03X222779Y190406I-508J-731D01*
G01X221866D01*
X221405Y190866D01*
Y191614D01*
X221622Y191832D01*
X222734D01*
X223688Y192785D01*
Y192820D01*
X223696Y192829D01*
Y194885D01*
X223688Y194894D01*
Y194919D01*
X222648Y195958D01*
X222622D01*
X222453Y196128D01*
X215758D01*
X214949Y196937D01*
Y198782D01*
X215046Y198879D01*
X217548D01*
X218423Y199754D01*
Y208387D01*
X217673Y209137D01*
X215070D01*
X214870Y209336D01*
Y211191D01*
X214597Y211464D01*
Y211622D01*
X214005Y212214D01*
X213847D01*
X213792Y212270D01*
X212566D01*
X212022Y212814D01*
Y213721D01*
X212510Y214209D01*
X214180D01*
X214195Y214224D01*
X217075D01*
X217472Y214621D01*
Y217631D01*
X218058Y218217D01*
G37*
G36*
G01X224969Y199900D02*
Y201599D01*
X225273Y201903D01*
X229132D01*
X229719Y201316D01*
Y200263D01*
X229015Y199559D01*
X225310D01*
X224969Y199900D01*
G37*
G36*
G01X238495Y218194D02*
X244806D01*
X245627Y217373D01*
Y215227D01*
X245410Y215010D01*
X243210D01*
X242900Y214700D01*
Y212727D01*
X242398Y212225D01*
X241590D01*
X240579Y211214D01*
X238332D01*
X237334Y212212D01*
Y213308D01*
X236407Y214235D01*
X236114D01*
Y214246D01*
X233814D01*
Y214235D01*
X232270D01*
Y214246D01*
X229720D01*
X229529Y214056D01*
Y212622D01*
X229280Y212373D01*
X224949D01*
X224652Y212670D01*
Y217353D01*
X225493Y218194D01*
X228357D01*
X228379Y218189D01*
G03X228702Y218151I324J1364D01*
G03X229025Y218189I-1J1402D01*
G01X229047Y218194D01*
X234656D01*
X234678Y218189D01*
G03X235001Y218151I324J1364D01*
G03X235324Y218189I-1J1402D01*
G01X235346Y218194D01*
X237805D01*
X237827Y218189D01*
G03X238150Y218151I324J1364D01*
G03X238473Y218189I-1J1402D01*
G01X238495Y218194D01*
G37*
G36*
G01X221617Y284778D02*
X223228D01*
X223350Y284655D01*
Y274101D01*
X223500Y273951D01*
Y271900D01*
X222660Y271060D01*
X220760D01*
X216849Y274971D01*
Y276618D01*
X217043Y276812D01*
X219979D01*
X220897Y277730D01*
X220911D01*
X221338Y278157D01*
Y284499D01*
X221617Y284778D01*
G37*
G36*
G01X220085Y291847D02*
X227142D01*
X227484Y291504D01*
Y284782D01*
X227488Y284779D01*
Y281471D01*
X227953Y281006D01*
X231170D01*
X231358Y280818D01*
Y275064D01*
X230906Y274612D01*
X229853D01*
G02X229479Y275153I0J400D01*
G03X229592Y275773I-1638J619D01*
G03X227841Y277524I-1751J0D01*
G01X226176D01*
X226093Y277608D01*
X224794D01*
X224361Y278041D01*
Y288645D01*
X223429Y289577D01*
X220006D01*
X219871Y289712D01*
Y291633D01*
X220085Y291847D01*
G37*
G36*
G01X218452Y289462D02*
X219409Y288505D01*
X223075D01*
X223266Y288314D01*
Y285907D01*
X223138Y285779D01*
X219528D01*
X219518Y285789D01*
X216019D01*
X215765Y286043D01*
Y291632D01*
X215966Y291833D01*
X218204D01*
X218452Y291585D01*
Y289462D01*
G37*
G36*
G01X216258Y284715D02*
X219603D01*
X220178Y284139D01*
Y278545D01*
X219446Y277814D01*
X216628D01*
X216543Y277728D01*
X212956D01*
X212802Y277882D01*
Y279733D01*
X213210Y280140D01*
X214820D01*
X215788Y281108D01*
Y284245D01*
X216258Y284715D01*
G37*
G36*
G01X237506Y187874D02*
X238790D01*
Y187840D01*
X239256Y187374D01*
Y184076D01*
X239769Y183563D01*
Y177930D01*
X239581Y177742D01*
X237226D01*
X236899Y178069D01*
Y179594D01*
X236552Y179941D01*
X235136D01*
X235127Y179942D01*
G03X235001Y179948I-125J-1296D01*
G03X234875Y179942I-1J-1302D01*
G01X234866Y179941D01*
X233112D01*
X232877Y180176D01*
Y182794D01*
X232337Y183334D01*
X230832D01*
X230298Y183868D01*
Y185685D01*
X230804Y186190D01*
X235818D01*
X235846Y186219D01*
X236525D01*
X236744Y186438D01*
X236962Y186655D01*
Y187330D01*
X237506Y187874D01*
G37*
G36*
G01X240599Y185869D02*
X241656D01*
X242918Y184607D01*
Y180648D01*
X242270Y180000D01*
Y171608D01*
X241998Y171336D01*
X240857D01*
X240617Y171576D01*
Y177362D01*
X240770Y177515D01*
Y183978D01*
X240617Y184131D01*
Y184148D01*
X240383Y184382D01*
Y185653D01*
X240599Y185869D01*
G37*
G36*
G01X234035Y178940D02*
X235759D01*
Y177533D01*
X236423Y176869D01*
X236683D01*
X236811Y176740D01*
X239616D01*
Y174628D01*
X239515Y174527D01*
X234432D01*
X234035Y174924D01*
Y178940D01*
G37*
G36*
G01X227636Y186085D02*
X229296D01*
Y183453D01*
X229630Y183120D01*
Y181967D01*
X229601Y181920D01*
G03X229474Y181455I763J-458D01*
G01Y181200D01*
X229163Y180889D01*
X227907D01*
X227387Y181409D01*
Y184029D01*
X227412Y184054D01*
Y185862D01*
X227636Y186085D01*
G37*
G36*
G01X234614Y198455D02*
X235791D01*
X236852Y197746D01*
Y197566D01*
G03X237244Y196829I890J1D01*
G01Y192546D01*
X236044Y191346D01*
Y187833D01*
X235403Y187192D01*
X231058D01*
X230594Y187656D01*
Y189616D01*
X230799Y189821D01*
X232821D01*
X233671Y190671D01*
Y191360D01*
X234941Y192630D01*
Y194812D01*
X234934Y194820D01*
Y194969D01*
X233959Y195944D01*
Y196966D01*
G03X234198Y197573I-651J607D01*
G01Y198040D01*
X234614Y198455D01*
G37*
G36*
G01X239753Y200072D02*
X237636D01*
X237393Y200315D01*
Y201997D01*
X237598Y202202D01*
X242592D01*
X243080Y201714D01*
Y197050D01*
X242588Y196558D01*
X240844D01*
X240720Y196681D01*
X240331Y197070D01*
Y199494D01*
X239753Y200072D01*
G37*
G36*
G01X245412Y195776D02*
X246710D01*
X246823Y195662D01*
X247913D01*
X248036Y195539D01*
Y195183D01*
X248038Y195181D01*
Y193757D01*
X248047Y193749D01*
Y193730D01*
X248786Y192991D01*
X249993D01*
X250060Y192924D01*
G02X250006Y192313I-283J-283D01*
G03X249447Y191244I743J-1069D01*
G03X250291Y190025I1302J0D01*
G01X250421Y189976D01*
Y189509D01*
X250178Y189265D01*
X250150Y189251D01*
G03X249447Y188095I599J-1156D01*
G03X250291Y186876I1302J0D01*
G01X250421Y186827D01*
Y186213D01*
X250291Y186164D01*
G03Y183726I458J-1219D01*
G01X250421Y183677D01*
Y183063D01*
X250291Y183014D01*
G03X249447Y181795I458J-1219D01*
G03X250749Y180493I1302J0D01*
G03X251143Y180554I0J1303D01*
G01X251173Y180564D01*
X253368D01*
G03X253643Y180574I11J3481D01*
G01X253651Y180575D01*
X256051D01*
X256758Y179868D01*
Y175239D01*
X257790Y174207D01*
X269893D01*
X272326Y171774D01*
Y162363D01*
X271400Y161437D01*
X250327D01*
X248940Y162824D01*
X248939Y162907D01*
G03X247646Y164200I-1302J-9D01*
G01X247563Y164201D01*
X247216Y164548D01*
X247421Y164754D01*
X247512Y164748D01*
G03X247599Y164745I88J1299D01*
G03Y167349I0J1302D01*
G03X246325Y166314I0J-1302D01*
G02X245650Y166114I-392J82D01*
G01X245047Y166717D01*
Y168040D01*
G03Y170354I-597J1157D01*
G01Y170713D01*
X244783Y170977D01*
X244950Y171144D01*
X244984Y171159D01*
G03X245752Y172347I-535J1188D01*
G03X244450Y173649I-1302J0D01*
G03X244133Y173610I-1J-1302D01*
G02X243636Y173998I-97J388D01*
G01Y174325D01*
X243879D01*
X243918Y174308D01*
G03X244450Y174194I533J1188D01*
G03Y176798I0J1302D01*
G03X244133Y176759I-1J-1302D01*
G02X243636Y177147I-97J388D01*
G01Y177475D01*
X243879D01*
X243918Y177458D01*
G03X244450Y177344I533J1188D01*
G03Y179948I0J1302D01*
G03X244119Y179905I1J-1302D01*
G01X244007Y179876D01*
X243785Y180099D01*
X243920Y180233D01*
Y180530D01*
X244142D01*
X244163Y180525D01*
G03X244450Y180493I287J1271D01*
G03Y183097I0J1302D01*
G03X244163Y183065I0J-1303D01*
G01X244142Y183060D01*
X243920D01*
Y183680D01*
X244142D01*
X244163Y183675D01*
G03X244450Y183643I287J1271D01*
G03Y186247I0J1302D01*
G03X243573Y185907I0J-1301D01*
G02X243021Y185920I-269J296D01*
G01X242071Y186870D01*
X241236D01*
X241211Y186895D01*
X240692D01*
X240338Y187249D01*
Y188364D01*
X239839Y188863D01*
X239592D01*
Y188876D01*
X237167D01*
X237046Y188997D01*
Y190897D01*
X237522Y191374D01*
X239991D01*
X239999Y191183D01*
G03X241300Y189942I1301J61D01*
G03X242592Y191087I0J1301D01*
G01X242601Y191155D01*
X242791Y191345D01*
X243179Y190957D01*
X243193Y190906D01*
G03X244450Y189942I1257J338D01*
G03X245752Y191244I0J1302D01*
G03X245227Y192289I-1303J0D01*
G01Y195591D01*
X245412Y195776D01*
G37*
G36*
G01X232611Y284966D02*
X234484D01*
X234568Y284882D01*
Y277858D01*
X234598Y277828D01*
Y276341D01*
X234609Y276331D01*
Y275019D01*
X237970Y271658D01*
Y270018D01*
G03Y267582I1328J-1218D01*
G01Y264480D01*
X237859Y264425D01*
G03X237029Y263081I673J-1344D01*
G03X237374Y262123I1503J0D01*
G02X237362Y261854I-154J-128D01*
G01X236751Y261243D01*
X234060D01*
X234038Y261418D01*
G03X232300Y262952I-1738J-218D01*
G03X231729Y262856I1J-1752D01*
G02X231199Y263234I-130J378D01*
G01Y265980D01*
G03X231955Y267085I-1003J1497D01*
G01X231967Y267141D01*
X232399Y267573D01*
Y267630D01*
G02X232794Y268030I400J0D01*
G03X234275Y269532I-21J1502D01*
G03X233158Y270984I-1502J0D01*
G02X232974Y271650I102J387D01*
G03X233402Y272700I-1074J1050D01*
G03X232517Y274069I-1501J0D01*
G01X232399Y274123D01*
Y284754D01*
X232611Y284966D01*
G37*
G36*
G01X235570Y284814D02*
X235684Y284928D01*
X237469D01*
X238650Y283747D01*
Y281357D01*
X239364Y280643D01*
X239283Y280508D01*
G03X238956Y279347I1904J-1163D01*
G03X241188Y277116I2231J0D01*
G01X243014D01*
G03X244592Y277769I1J2231D01*
G01X245065Y278242D01*
X250772D01*
X251170Y277843D01*
Y276756D01*
G03X251667Y275353I2232J1D01*
G01Y273981D01*
X251664Y273963D01*
G03X251636Y273655I1724J-312D01*
G03X251653Y273417I1752J6D01*
G01X251666Y273319D01*
X250892Y272545D01*
X243090D01*
G03X241084I-1003J-1118D01*
G01X239623D01*
X235610Y276558D01*
Y276774D01*
X235600Y276784D01*
Y278243D01*
X235570Y278273D01*
Y284814D01*
G37*
G36*
G01X228628Y294944D02*
X230215D01*
X235021Y290138D01*
X253300D01*
X253768Y289669D01*
Y285024D01*
X252322Y283578D01*
G03X251870Y282926I1579J-1577D01*
G02X251315Y282740I-364J166D01*
G03X250252Y283010I-1064J-1962D01*
G01X244445D01*
G03X243557Y282825I2J-2232D01*
G02X243010Y283095I-159J367D01*
G03X241263Y284456I-1747J-441D01*
G03X240091Y284023I0J-1803D01*
G01X239950Y283903D01*
X237886Y285967D01*
X231396D01*
X230433Y285004D01*
X228679D01*
X228486Y285197D01*
Y294802D01*
X228628Y294944D01*
G37*
G36*
G01X249208Y75900D02*
G03I-508J0D01*
G37*
G36*
G01X251621Y102919D02*
G03I-508J0D01*
G37*
G36*
G01X254905Y103697D02*
G03I-508J0D01*
G37*
G36*
G01X245495Y103528D02*
G03I-508J0D01*
G37*
G36*
G01X248480Y198464D02*
G03X248648Y198487I-1J632D01*
G01X248760Y198518D01*
X249477Y197801D01*
X249462Y197701D01*
G03X249447Y197506I1287J-197D01*
G03X250749Y196204I1302J0D01*
G03X250944Y196219I-2J1302D01*
G01X251044Y196234D01*
X251090Y196188D01*
X254715D01*
X255408Y195495D01*
Y190492D01*
X252846D01*
G03X252668Y190487I9J-3482D01*
G01X252580Y190482D01*
X252381Y190681D01*
Y193368D01*
X251726Y194023D01*
X249189D01*
X249040Y194172D01*
Y195596D01*
X249038Y195598D01*
Y196286D01*
X248660Y196664D01*
X247238D01*
X246685Y197217D01*
Y197998D01*
X247152Y198464D01*
X248480D01*
G37*
G36*
G01X260252Y227810D02*
X273070D01*
X274030Y226850D01*
Y222623D01*
X273935Y222528D01*
X270819D01*
X269212Y224135D01*
X264942D01*
X262746Y221939D01*
Y215843D01*
G03X262078Y214593I834J-1249D01*
G03X262746Y213343I1502J-1D01*
G01Y208964D01*
G02X262550Y208764I-200J0D01*
G03Y205760I30J-1502D01*
G02X262746Y205560I-4J-200D01*
G01Y203316D01*
X258765Y199335D01*
X258480D01*
G02X258143Y199951I0J400D01*
G03X258350Y200655I-1094J704D01*
G03X255746I-1302J0D01*
G03X255953Y199951I1301J0D01*
G02X255616Y199335I-337J-216D01*
G01X253174D01*
X252694Y199815D01*
Y200942D01*
X253326Y201574D01*
X254213D01*
X254487Y201848D01*
X254586D01*
Y201946D01*
X254817Y202178D01*
Y204261D01*
X252565Y206513D01*
X252450D01*
G02X252051Y206923I1J400D01*
G01Y206955D01*
G03X249447I-1302J0D01*
G03X249464Y206745I1302J0D01*
G01X249467Y206729D01*
Y206513D01*
X248881D01*
Y206729D01*
X248884Y206745D01*
G03X248901Y206955I-1285J210D01*
G03X247599Y208257I-1302J0D01*
G03X246683Y207880I0J-1301D01*
G02X246119Y207881I-281J284D01*
G01X245700Y208300D01*
X243700D01*
X243500Y208500D01*
Y210300D01*
X245232Y212032D01*
X245289Y212045D01*
G03X245740Y212300I-194J869D01*
G01X246713D01*
G03X248485I886J954D01*
G01X249863D01*
G03X250749Y211952I886J954D01*
G03X252051Y213254I0J1302D01*
G03X252022Y213528I-1302J1D01*
G01X251999Y213634D01*
X252537Y214172D01*
X252777Y213931D01*
X252718Y213804D01*
G03X252596Y213254I1179J-550D01*
G03X253898Y214556I1302J0D01*
G03X253184Y214343I0J-1303D01*
G02X252565Y214677I-219J335D01*
G01Y218130D01*
G02X253184Y218464I400J-1D01*
G03X253898Y218251I714J1090D01*
G03Y220855I0J1302D01*
G03X253540Y220805I-1J-1302D01*
G02X253320Y221109I-54J192D01*
G03X253429Y221308I-1021J689D01*
G02X253650Y221425I184J-79D01*
G03X253898Y221401I249J1278D01*
G03X255200Y222703I0J1302D01*
G03X254613Y223791I-1302J0D01*
G02X254550Y224408I220J334D01*
G01X257010Y226868D01*
X258800D01*
G03X259671Y227229I0J1231D01*
G01X260252Y227810D01*
G37*
G36*
G01X251220Y396300D02*
X255100D01*
X256300Y395100D01*
Y388770D01*
X258820Y386250D01*
Y382850D01*
X261680Y379990D01*
Y366400D01*
X262380Y365700D01*
X265300D01*
X267800Y368200D01*
X271498D01*
Y364558D01*
X270645Y363705D01*
G03X270167Y362901I1345J-1344D01*
G01X270153Y362853D01*
X269800Y362500D01*
Y360300D01*
X270620Y359480D01*
X277280D01*
X278310Y358450D01*
Y354880D01*
X278010Y354580D01*
X276330D01*
X274780Y356130D01*
X261670D01*
X257352Y360449D01*
Y360806D01*
G03X257342Y360988I-1752J-5D01*
G01X257335Y361055D01*
G03X257242Y361462I-1742J-184D01*
G01X257237Y361476D01*
G03X257169Y361640I-1650J-588D01*
G01X257150Y361681D01*
Y363140D01*
X252970Y367320D01*
Y384650D01*
X250560Y387060D01*
Y395640D01*
X251220Y396300D01*
G37*
G36*
G01X260267Y103651D02*
G03I-508J0D01*
G37*
G36*
G01X265549Y134814D02*
X269835D01*
X270400Y134248D01*
X271951D01*
X272400Y133800D01*
Y132616D01*
X272398Y132615D01*
Y132198D01*
X269783Y129583D01*
X265484D01*
X265108Y129959D01*
Y134373D01*
X265549Y134814D01*
G37*
G36*
G01X264613Y139401D02*
X265041Y139829D01*
X277871D01*
X278900Y138800D01*
Y135900D01*
X278250Y135250D01*
X270815D01*
X270250Y135815D01*
X265055D01*
X264613Y136257D01*
Y139401D01*
G37*
G36*
G01X279500Y167500D02*
X282900D01*
X283600Y166800D01*
X286400D01*
X286822Y166378D01*
Y163822D01*
X287807Y162836D01*
X290776Y159867D01*
X290784Y159799D01*
G03X292346Y158237I1788J226D01*
G01X292414Y158229D01*
X296546Y154097D01*
Y151476D01*
X296541Y151453D01*
G03X296503Y151118I1464J-336D01*
G03X296541Y150783I1502J1D01*
G01X296546Y150760D01*
Y148976D01*
X296541Y148953D01*
G03X296503Y148618I1464J-336D01*
G03X296541Y148283I1502J1D01*
G01X296546Y148260D01*
Y147427D01*
X296367Y147248D01*
X281833D01*
X281335Y147746D01*
Y149212D01*
X281592Y149469D01*
X286755D01*
X286762Y149476D01*
X287045D01*
X288927Y151358D01*
Y157593D01*
X284220Y162300D01*
X284199D01*
X283798Y162702D01*
X279185D01*
X279184Y162700D01*
X279102D01*
X273900Y157498D01*
X266852D01*
X264402Y155048D01*
Y154552D01*
X264388Y154539D01*
Y149525D01*
X264402Y149512D01*
Y148981D01*
X265006Y148377D01*
X266829D01*
X267201Y148005D01*
Y146729D01*
X266723Y146252D01*
X264511D01*
X264505Y146245D01*
X261302D01*
X258650Y148897D01*
Y159791D01*
X259294Y160436D01*
X271815D01*
X271898Y160519D01*
X272219D01*
X275200Y163500D01*
X277700D01*
X279200Y165000D01*
Y167200D01*
X279500Y167500D01*
G37*
G36*
G01X267501Y156235D02*
X273668D01*
X273843Y156060D01*
Y151143D01*
X274426Y150560D01*
X278999D01*
X279285Y150275D01*
G03X279290Y150266I1315J725D01*
G01Y146926D01*
X278695Y146331D01*
X270581D01*
X270054Y146858D01*
Y149158D01*
X269644Y149568D01*
X265762D01*
X265390Y149940D01*
Y154124D01*
X267501Y156235D01*
G37*
G36*
G01X264926Y145250D02*
X273043D01*
X273761Y144532D01*
Y141369D01*
X273223Y140831D01*
X265145D01*
X264604Y141372D01*
Y141625D01*
Y144928D01*
X264926Y145250D01*
G37*
G36*
G01X265429Y223133D02*
X268715D01*
X271341Y220507D01*
X277503D01*
X277846Y220164D01*
Y217400D01*
X277512Y217066D01*
X274535D01*
X273618Y217983D01*
X272115D01*
X272081Y217996D01*
G03X271470Y218106I-611J-1642D01*
G01X271152D01*
G03X270541Y217996I0J-1752D01*
G01X270507Y217983D01*
X270230D01*
X269815Y217568D01*
X264904D01*
X264264Y218207D01*
Y221968D01*
X265429Y223133D01*
G37*
G36*
G01X273605Y256285D02*
X273966Y255924D01*
Y250485D01*
X272944Y249462D01*
X266022D01*
X264999Y250485D01*
Y254304D01*
X266980Y256285D01*
X273605D01*
G37*
G36*
G01X267930Y268003D02*
X288246D01*
X288731Y267518D01*
Y259214D01*
X288284Y258767D01*
X267695D01*
X265500Y260962D01*
Y262658D01*
X266071Y263229D01*
G03X266432Y264100I-870J871D01*
G01Y266400D01*
G03X266427Y266506I-1232J-5D01*
G01X266419Y266599D01*
X267105Y267285D01*
X267144Y267300D01*
G03X267930Y268003I-544J1400D01*
G37*
G36*
G01X276409Y141342D02*
X276310Y141441D01*
Y144557D01*
X276431Y144678D01*
X279232D01*
X280724Y143186D01*
X283527D01*
X285100Y141613D01*
Y135200D01*
X280206Y130306D01*
X273994D01*
X273400Y130900D01*
Y132200D01*
X274350Y133150D01*
X278950D01*
X280400Y134600D01*
Y139600D01*
X279118Y140882D01*
X277571D01*
X277111Y141342D01*
X276409D01*
G37*
G36*
G01X281581Y146246D02*
X296496D01*
X296504Y146054D01*
G03X296710Y145357I1501J65D01*
G01Y141655D01*
X296299Y141244D01*
X295437D01*
X293271Y139078D01*
Y136755D01*
X292912Y136396D01*
X287300D01*
X286102Y137594D01*
Y142028D01*
X284512Y143617D01*
Y143857D01*
X284172Y144197D01*
X281492D01*
X281356Y144333D01*
Y146020D01*
X281581Y146246D01*
G37*
G36*
G01X279600Y161700D02*
X283383D01*
X287540Y157543D01*
X287884Y157198D01*
Y152118D01*
X287326Y151560D01*
X285003D01*
X284947Y151667D01*
G03X283616Y152473I-1331J-696D01*
G03X282431Y151894I0J-1502D01*
G02X281801I-315J246D01*
G03X280616Y152473I-1185J-923D01*
G03X279286Y151669I0J-1502D01*
G01X279230Y151562D01*
X276416D01*
X275886Y152091D01*
Y157986D01*
X279600Y161700D01*
G37*
G36*
G01X274606Y172306D02*
X281566D01*
X282314Y171558D01*
X283944D01*
X286490Y169013D01*
Y167802D01*
X284247D01*
X284003Y168045D01*
X283771D01*
X283315Y168502D01*
X279085D01*
X278629Y168045D01*
X278345D01*
X277700Y167400D01*
Y165000D01*
X277201Y164502D01*
X274785D01*
X274684Y164400D01*
X274500D01*
X274000Y164900D01*
Y171700D01*
X274606Y172306D01*
G37*
G36*
G01X281500Y206200D02*
X286300D01*
X287100Y205400D01*
Y203600D01*
X286800Y203300D01*
X286258D01*
X286221Y203316D01*
G03X285544Y203452I-677J-1617D01*
G01X285449D01*
X285300Y203600D01*
X281300D01*
X281100Y203800D01*
Y205800D01*
X281500Y206200D01*
G37*
G36*
G01X277706Y227753D02*
X289999D01*
X290794Y226958D01*
Y225622D01*
X293116Y223300D01*
X295521D01*
X296890Y221931D01*
Y221257D01*
X298089Y220058D01*
X302443D01*
X304180Y221795D01*
X310944D01*
X311510Y221229D01*
Y218274D01*
X310666Y217430D01*
G03X310518Y217282I551J-699D01*
G01X308698Y215462D01*
X308620Y215470D01*
G03X308460Y215480I-161J-1292D01*
G03X308260Y215465I-3J-1302D01*
G03X307158Y214201I200J-1287D01*
G01X307155Y214002D01*
X296396D01*
X291849Y218549D01*
X285388D01*
X283969Y217130D01*
X280377D01*
X280268Y217239D01*
Y221088D01*
X279108Y222248D01*
X276006D01*
Y226053D01*
X277706Y227753D01*
G37*
G36*
G01X289098Y240098D02*
X285722D01*
X285624Y240000D01*
X281312D01*
X280912Y240400D01*
Y245560D01*
X282018Y246666D01*
X290000D01*
X290500Y246166D01*
Y244000D01*
X289500Y243000D01*
Y240500D01*
X289098Y240098D01*
G37*
G36*
G01X289565Y239149D02*
X289685D01*
X289920Y238914D01*
Y237248D01*
X289602Y236930D01*
X286496D01*
X285688Y236122D01*
Y230420D01*
X285055Y229787D01*
X281552D01*
X280973Y230366D01*
Y233027D01*
X280000Y234000D01*
X279300D01*
X278900Y234400D01*
Y235916D01*
X280992Y238008D01*
X281529Y238544D01*
X281984Y238998D01*
X286039D01*
X286137Y239096D01*
X289513D01*
X289565Y239149D01*
G37*
G36*
G01X288699Y257354D02*
X290964D01*
X291414Y256903D01*
Y255344D01*
X288447Y252377D01*
Y247974D01*
X288140Y247668D01*
X282555D01*
X282220Y248002D01*
Y255961D01*
X282532Y256273D01*
X287618D01*
X288699Y257354D01*
G37*
G36*
G01X281216Y255925D02*
Y248345D01*
X280585Y247714D01*
X275502D01*
X274982Y248234D01*
Y255868D01*
X275387Y256273D01*
X280868D01*
X281216Y255925D01*
G37*
G36*
G01X295911Y139669D02*
X318539D01*
X318787Y139421D01*
Y137698D01*
X316201Y135112D01*
X309975D01*
X309966Y135113D01*
G03X309838Y135118I-120J-1426D01*
G01X296437D01*
X295575Y135980D01*
Y139333D01*
X295911Y139669D01*
G37*
G36*
G01X294845Y234052D02*
X301746D01*
X302608Y233190D01*
Y231451D01*
X339009D01*
X339147Y231313D01*
Y223916D01*
X338034Y222804D01*
X303711D01*
X302245Y221338D01*
X298452D01*
X298425Y221365D01*
Y223685D01*
X296832Y225278D01*
X292974D01*
X292650Y225602D01*
Y231857D01*
X294845Y234052D01*
G37*
G36*
G01X301025Y245151D02*
X305230D01*
X305905Y244476D01*
Y235779D01*
X305209Y235083D01*
X303017D01*
G02X302618Y235513I0J400D01*
G03X302622Y235626I-1498J110D01*
G03X301968Y236865I-1501J0D01*
G02Y237526I226J330D01*
G03X302622Y238765I-847J1239D01*
G03X299618I-1502J0D01*
G03X300272Y237526I1501J0D01*
G02Y236865I-226J-331D01*
G03X299618Y235626I847J-1239D01*
G03X299622Y235513I1502J-3D01*
G02X299223Y235083I-399J-30D01*
G01X294460D01*
X291405Y232028D01*
Y230740D01*
X290282Y229617D01*
X287906D01*
X287894Y229629D01*
X287030D01*
X286672Y229987D01*
X286690Y230005D01*
Y235660D01*
X286764Y235735D01*
X290090D01*
X297800Y243445D01*
G02X298082I141J-142D01*
G03X299138Y243011I1056J1068D01*
G03X300640Y244513I0J1502D01*
G03X300628Y244701I-1502J-1D01*
G02X301025Y245151I397J50D01*
G37*
G36*
G01X297009Y461651D02*
X297128Y461770D01*
Y470572D01*
X297132Y470576D01*
X298622D01*
Y461976D01*
X298628D01*
Y461729D01*
X298788Y461569D01*
X300023D01*
X300080Y461512D01*
Y449868D01*
X302278Y447670D01*
X330330D01*
X332365Y445635D01*
Y427635D01*
X336600Y423400D01*
X346887D01*
X348962Y421325D01*
Y348462D01*
X336720Y336220D01*
Y323220D01*
X335500Y322000D01*
X324500D01*
X323500Y323000D01*
Y343000D01*
X339384Y358884D01*
Y397931D01*
X336396Y400919D01*
X315781D01*
X315300Y401400D01*
Y429900D01*
X307100Y438100D01*
X295400D01*
X294768Y438732D01*
Y452442D01*
X294908Y452582D01*
Y462978D01*
X294900D01*
Y468988D01*
X296230D01*
X296260Y468958D01*
Y461976D01*
X296265D01*
Y461778D01*
X296392Y461651D01*
X297009D01*
G37*
G36*
G01X292402Y470576D02*
X293898D01*
Y461976D01*
X293907D01*
Y452997D01*
X293477Y452567D01*
X290374D01*
X290196Y452744D01*
Y461674D01*
G03X290064Y462275I-1431J1D01*
G01X290046Y462314D01*
Y470562D01*
X290060Y470576D01*
X291534D01*
Y461976D01*
X292402D01*
Y470576D01*
G37*
G36*
G01X315812Y253339D02*
X338306D01*
X339216Y252429D01*
Y232522D01*
X339146Y232452D01*
X308717D01*
X307874Y233295D01*
Y250816D01*
X308018Y250857D01*
G03X309102Y252300I-418J1443D01*
G03X309023Y252781I-1502J0D01*
G01X308983Y252898D01*
X309353Y253268D01*
X315400D01*
G03X315782Y253329I-1J1232D01*
G01X315812Y253339D01*
G37*
G36*
G01X311070Y311450D02*
X331490D01*
X332570Y310370D01*
Y287270D01*
X331158Y285858D01*
X313000D01*
G03X311670Y286662I-1330J-698D01*
G03X311237Y286598I1J-1502D01*
G01X311122Y286564D01*
X310623Y287063D01*
Y293604D01*
G03Y295974I-923J1185D01*
G01Y311003D01*
X311070Y311450D01*
G37*
G36*
G01X334000Y397860D02*
Y393666D01*
X333000Y392666D01*
X314261D01*
X313574Y393353D01*
Y398029D01*
X314105Y398560D01*
X333300D01*
X334000Y397860D01*
G37*
G36*
G01X314385Y467812D02*
X315625D01*
X315966Y467471D01*
Y453751D01*
X315647Y453432D01*
X314431D01*
X313969Y453894D01*
Y467396D01*
X314385Y467812D01*
G37*
G36*
G01X320725Y135464D02*
X338233D01*
X338622D01*
X339063D01*
X344600D01*
X345500Y134564D01*
Y116000D01*
X344600Y115100D01*
X337100D01*
X335700Y116500D01*
X331429D01*
X330229Y117700D01*
Y121764D01*
X330829Y122364D01*
X332729D01*
X333579Y123214D01*
Y127914D01*
X332629Y128864D01*
X320350D01*
X320200Y129014D01*
Y134939D01*
X320725Y135464D01*
G37*
G36*
G01X323229Y127764D02*
X327429D01*
X327629Y127564D01*
Y115553D01*
X326740Y114664D01*
X323370D01*
X322929Y115105D01*
Y127464D01*
X323229Y127764D01*
G37*
G36*
G01X324829Y136864D02*
Y141764D01*
Y145522D01*
X325171Y145864D01*
X325271Y145964D01*
X330129D01*
X338629D01*
X339329Y145264D01*
Y137164D01*
X338729Y136564D01*
X325129D01*
X324829Y136864D01*
G37*
G36*
G01X328100Y176400D02*
X329230D01*
X330000Y175919D01*
Y175443D01*
X329989Y175411D01*
G03X329903Y174911I1416J-501D01*
G03X329989Y174411I1502J1D01*
G01X330000Y174379D01*
Y174300D01*
X330062Y174238D01*
X330076Y174211D01*
G03X330705Y173582I1329J700D01*
G01X330732Y173568D01*
X330800Y173500D01*
X330889D01*
X330920Y173489D01*
G03X331405Y173409I484J1422D01*
G03X331797Y173461I0J1502D01*
G01X331909Y173491D01*
X332400Y173000D01*
Y171500D01*
X332132Y171232D01*
X332007Y171287D01*
G03X331405Y171413I-602J-1375D01*
G03X330677Y171225I0J-1502D01*
G01X330632Y171200D01*
X330500D01*
X329600Y170300D01*
X328400D01*
X327900Y170800D01*
Y176200D01*
X328100Y176400D01*
G37*
G36*
G01X327674Y199114D02*
X337817D01*
X338527Y198404D01*
Y195403D01*
X338193Y195069D01*
X338067D01*
X338032Y195082D01*
G03X336768I-632J-1633D01*
G01X336733Y195069D01*
X327699D01*
X327268Y195500D01*
Y198708D01*
X327674Y199114D01*
G37*
G36*
G01X319818Y199402D02*
X323530D01*
X323531Y199400D01*
X325607D01*
X326130Y198878D01*
Y194257D01*
X325499Y193626D01*
X319617D01*
X318850Y194393D01*
Y198810D01*
X319434Y199394D01*
X319522Y199390D01*
G03X319601Y199388I84J1750D01*
G03X319807Y199401I-7J1752D01*
G01X319818Y199402D01*
G37*
G36*
G01X320198Y218030D02*
X329807D01*
X330425Y217412D01*
Y201271D01*
X329556Y200402D01*
X323946D01*
X323580Y200768D01*
Y208140D01*
X323554Y208166D01*
Y208700D01*
X322896Y209358D01*
X322132D01*
X322108Y209364D01*
G03X321686Y209416I-424J-1700D01*
G01X320145D01*
X319504Y210056D01*
Y217336D01*
X320198Y218030D01*
G37*
G36*
G01X343408Y66100D02*
G03I-508J0D01*
G37*
G36*
G01X331876Y211766D02*
X337829D01*
X338705Y210890D01*
Y201443D01*
X337686Y200424D01*
X331747D01*
X331453Y200718D01*
Y211343D01*
X331876Y211766D01*
G37*
%LPC*%
G75*
G36*
G01X29685Y236898D02*
X28598Y237985D01*
Y243215D01*
X29485Y244102D01*
X35715D01*
X37602Y242215D01*
Y237185D01*
X36415Y235998D01*
X34585D01*
X33685Y236898D01*
X29685D01*
G37*
G36*
G01X14826Y225595D02*
G03Y226141I-292J273D01*
G02X14420Y227168I1096J1027D01*
G02X15922Y228670I1502J0D01*
G02X16909Y228300I0J-1501D01*
G03X17435I263J302D01*
G02X18422Y228670I987J-1131D01*
G02X19512Y228202I0J-1503D01*
G03X20054Y228166I290J275D01*
G02X21000Y228502I947J-1166D01*
G02X22502Y227000I0J-1502D01*
G02X22132Y226013I-1501J0D01*
G03Y225487I302J-263D01*
G02X22502Y224500I-1131J-987D01*
G02X21000Y222998I-1502J0D01*
G02X19953Y223423I0J1502D01*
G03X19411Y223437I-279J-287D01*
G02X18422Y223066I-988J1131D01*
G02X17435Y223436I0J1501D01*
G03X16909I-263J-302D01*
G02X15922Y223066I-987J1131D01*
G02X14420Y224568I0J1502D01*
G02X14826Y225595I1502J0D01*
G37*
G36*
G01X71311Y311477D02*
Y311476D01*
X72489D01*
Y311477D01*
G02X72973Y311338I6J-890D01*
G01X73022Y311306D01*
X76079D01*
G02X76950Y310946I1J-1231D01*
G01X77301Y310594D01*
X80061D01*
G02X80562Y310093I0J-501D01*
G01Y306693D01*
G02X80061Y306192I-501J0D01*
G01X75461D01*
G02X74960Y306693I0J501D01*
G01Y308844D01*
X73150D01*
Y308155D01*
X73201Y308098D01*
G02X73652Y306925I-1300J-1173D01*
G01Y302725D01*
X73938Y302438D01*
G02X74428Y301488I-1237J-1240D01*
G01X74438Y301425D01*
X74625Y301238D01*
X74960Y301572D01*
Y303597D01*
G02X75461Y304098I501J0D01*
G01X80061D01*
G02X80562Y303597I0J-501D01*
G01Y300197D01*
G02X80061Y299696I-501J0D01*
G01X78036D01*
X77476Y299136D01*
Y296700D01*
G02X77327Y295991I-1751J-2D01*
G01X77310Y295952D01*
Y295450D01*
X76952D01*
G02X75725Y294948I-1228J1250D01*
G01X74601D01*
G02X73363Y295462I1J1751D01*
G01X71462Y297363D01*
G02X70948Y298601I1237J1239D01*
G01Y300475D01*
X70662Y300762D01*
G02X70148Y302000I1237J1239D01*
G01Y306925D01*
G02X70650Y308152I1752J-1D01*
G01Y309534D01*
X70414D01*
Y310587D01*
G02X71311Y311477I890J0D01*
G37*
G36*
G01X93311Y328787D02*
X93288D01*
G02X94790Y330289I0J1502D01*
G02X94664Y329687I-1501J0D01*
G03X95037Y329127I366J-160D01*
G01X95060D01*
G02X96562Y327625I0J-1502D01*
G02X96552Y327448I-1502J-4D01*
G03X97128Y327043I397J-47D01*
G02X97800Y327202I673J-1343D01*
G02X96298Y325700I0J-1502D01*
G02X96308Y325877I1502J4D01*
G03X95732Y326282I-397J47D01*
G02X95060Y326123I-673J1343D01*
G02X93558Y327625I0J1502D01*
G02X93684Y328227I1501J0D01*
G03X93311Y328787I-366J160D01*
G37*
G36*
G01X86986Y348435D02*
G02X86315Y349574I631J1139D01*
G02X88919I1302J0D01*
G02X88248Y348435I-1302J0D01*
G01Y342697D01*
X89147Y341799D01*
G02X89332Y341352I-448J-447D01*
G01Y338708D01*
X89444Y338654D01*
G02X90402Y337123I-744J-1531D01*
G02X90132Y336202I-1702J-1D01*
G01Y331893D01*
X90141Y331863D01*
G02X90186Y331587I-845J-279D01*
G01Y330534D01*
X90031D01*
X89975Y330424D01*
G02X89972Y330418I-1282J637D01*
G01X89950Y330375D01*
Y328625D01*
X89972Y328582D01*
G02X89975Y328576I-1279J-643D01*
G01X90031Y328466D01*
X90186D01*
Y327413D01*
G02X90141Y327137I-890J3D01*
G01X90132Y327107D01*
Y319395D01*
G02X90502Y318300I-1432J-1094D01*
G02X90132Y317205I-1802J-1D01*
G01Y312093D01*
X90712Y311512D01*
G02X91132Y310500I-1012J-1013D01*
G01Y305568D01*
G02X90712Y304556I-1432J1D01*
G01X88830Y302674D01*
Y300197D01*
G02X88329Y299696I-501J0D01*
G01X83729D01*
G02X83228Y300197I0J501D01*
G01Y303597D01*
G02X83729Y304098I501J0D01*
G01X86206D01*
X88268Y306161D01*
Y309907D01*
X87688Y310488D01*
G02X87268Y311500I1012J1013D01*
G01Y317205D01*
G02X86898Y318300I1432J1094D01*
G02X87268Y319395I1802J1D01*
G01Y325379D01*
G03X86581Y325657I-400J0D01*
G02X85500Y325198I-1081J1043D01*
G02Y328202I0J1502D01*
G02X86538Y327786I0J-1503D01*
G03X87214Y328075I276J289D01*
G01Y328466D01*
X87369D01*
X87425Y328576D01*
G02X87428Y328582I1282J-637D01*
G01X87450Y328625D01*
Y330375D01*
X87428Y330418D01*
G02X87425Y330424I1279J643D01*
G01X87369Y330534D01*
X87214D01*
Y331587D01*
G02X87259Y331863I890J-3D01*
G01X87268Y331893D01*
Y336202D01*
G02X86998Y337123I1432J920D01*
G02X87956Y338654I1702J0D01*
G01X88068Y338708D01*
Y341090D01*
X87170Y341988D01*
G02X86986Y342435I448J446D01*
G01Y348435D01*
G37*
G36*
G01X76041Y371322D02*
X76247D01*
X76999Y372074D01*
X77014Y372108D01*
G02X78206Y372886I1192J-524D01*
G02X79508Y371584I0J-1302D01*
G02X78916Y370493I-1301J0D01*
G01Y369654D01*
X78560Y369422D01*
X77882D01*
X77138Y368678D01*
X76041D01*
X75268Y369452D01*
Y370548D01*
X76041Y371322D01*
G37*
G54D99*
X46220Y277170D03*
X118692Y137304D03*
X138100Y213600D03*
X152556Y147683D03*
X152500Y199500D03*
X151040Y237870D03*
G54D100*
X90766Y349574D03*
X87617Y355873D03*
X93916D03*
X90766D03*
X75056D03*
Y352724D03*
X81355Y355873D03*
X68757Y377883D03*
Y374733D03*
X90766Y362173D03*
X181495Y197506D03*
X187794Y213254D03*
X178346Y210104D03*
X175196D03*
Y213254D03*
X178346Y225852D03*
X181495Y219553D03*
X184645D03*
X181495Y222703D03*
X187794Y219553D03*
X175196Y229002D03*
X187794Y172347D03*
Y181795D03*
Y178646D03*
X235001Y166047D03*
X228702Y169197D03*
X228739Y216441D03*
X247599Y191244D03*
X250749Y169197D03*
X253898D03*
X247599Y175496D03*
Y181795D03*
X253898Y172347D03*
Y178646D03*
X247599Y184945D03*
X250749Y175496D03*
Y178646D03*
Y172347D03*
X247599Y178646D03*
Y188095D03*
X244450D03*
X247599Y172347D03*
X257048D03*
X253898Y175496D03*
X257048Y213254D03*
X247599Y210104D03*
X257048Y206955D03*
X250749Y210104D03*
G54D98*
X39408Y195990D03*
X24705Y258767D03*
X17065Y255712D03*
X37485Y258807D03*
X41100Y248900D03*
X92698Y323224D03*
X148429Y147682D03*
G54D101*
X110900Y378500D03*
X111330Y357800D03*
%LPD*%
G75*
G36*
G01X29600Y242800D02*
X29900Y243100D01*
X35300D01*
X36600Y241800D01*
Y237600D01*
X36000Y237000D01*
X35000D01*
X34100Y237900D01*
X30100D01*
X29600Y238400D01*
Y242800D01*
G37*
G54D10*
X-56709Y43008D03*
X-61709Y56192D03*
X-51709D03*
X-61100Y250316D03*
X-56100Y263500D03*
X-61000Y382816D03*
X-56000Y396000D03*
X-51100Y250316D03*
X-51000Y382816D03*
X-30000Y43000D03*
X-35000Y56184D03*
X-25000D03*
X-25100Y250316D03*
X-35100D03*
X-30100Y263500D03*
X-36000Y418816D03*
X-26000D03*
X-31000Y432000D03*
G54D20*
X27300Y68200D03*
X340639Y432809D03*
G54D11*
G01X116500Y83711D02*
X115000D01*
X113000Y85711D01*
Y88500D01*
G01X125100Y86509D02*
X124383Y85792D01*
X122233D01*
X120152Y83711D01*
X116500D01*
X3000Y8494D03*
Y28494D03*
Y48494D03*
Y68494D03*
Y88494D03*
Y108494D03*
Y128494D03*
Y148494D03*
Y168494D03*
Y188494D03*
Y208494D03*
Y228494D03*
Y248494D03*
Y268494D03*
Y288494D03*
Y308494D03*
Y342126D03*
Y362126D03*
Y382126D03*
Y402126D03*
Y422126D03*
Y442126D03*
X9407Y10554D03*
X12900Y105500D03*
X19200Y102700D03*
X12500Y102000D03*
X16626Y195848D03*
X19129D03*
Y193048D03*
X16626D03*
X19129Y204248D03*
X17000Y208017D03*
Y211541D03*
X16626Y198648D03*
Y201448D03*
X19129Y198648D03*
Y201448D03*
X16626Y204248D03*
X17000Y215713D03*
Y219288D03*
X15922Y224568D03*
Y227168D03*
X18422Y224568D03*
Y227168D03*
X18000Y240900D03*
Y237900D03*
Y249900D03*
Y246900D03*
Y243900D03*
X15688Y259063D03*
X13736Y299891D03*
X6200Y312900D03*
X8300Y314700D03*
X13736Y303280D03*
X13827Y325310D03*
X13869Y352239D03*
X14000Y401700D03*
Y406700D03*
Y404200D03*
X17700Y427600D03*
X14600Y422500D03*
X14700Y425000D03*
X22218Y3000D03*
X27323Y25842D03*
X23723Y123791D03*
Y120791D03*
X32223Y123791D03*
Y120791D03*
X25200Y116300D03*
X31890Y110400D03*
X23736Y127758D03*
Y130758D03*
X32236Y127758D03*
Y130758D03*
X31920Y186610D03*
X21250Y206220D03*
X21000Y227000D03*
Y224500D03*
X21135Y236587D03*
X21205Y232767D03*
X21135Y240667D03*
Y243737D03*
X24690Y246467D03*
Y251967D03*
X21135Y246837D03*
X21035Y249937D03*
X24690Y249267D03*
X22237Y301237D03*
X30638Y301213D03*
X22237Y311481D03*
Y308592D03*
X30638Y309068D03*
X30700Y315500D03*
X25811Y319400D03*
X32000Y326300D03*
X23535Y329990D03*
X23810Y322534D03*
X31300Y329900D03*
X31000Y342500D03*
X34300Y375000D03*
X26300Y374400D03*
X31600Y379600D03*
X33100Y392100D03*
X32700Y395381D03*
X20600Y428900D03*
X25202Y425329D03*
X29400Y430900D03*
X23677Y422419D03*
X32100Y432800D03*
X20225Y447671D03*
X22692Y466518D03*
X42218Y3000D03*
X35044Y35751D03*
X45500Y41500D03*
X43926Y62248D03*
X35304Y58317D03*
X45500Y92500D03*
X45276Y98488D03*
X40340Y100710D03*
X45001Y95144D03*
X40723Y123791D03*
Y120791D03*
X49223Y123791D03*
Y121291D03*
X38300Y109200D03*
X48500Y112559D03*
X40736Y127758D03*
Y130758D03*
X49236Y127758D03*
Y130758D03*
X36599Y189016D03*
X37360Y194050D03*
X37823Y198346D03*
X47714Y212227D03*
X47948Y201000D03*
X39493Y222932D03*
X41993D03*
X44149Y227332D03*
X39493Y220332D03*
X41993D03*
X44149Y224732D03*
X48059Y214825D03*
X48023Y217860D03*
X39800Y213800D03*
X35700Y218000D03*
X40500Y236900D03*
X35600Y241200D03*
Y238200D03*
X41574Y255937D03*
X46220Y277170D03*
X47440Y301336D03*
Y308691D03*
X39039Y309044D03*
X47440Y312080D03*
X39039Y304278D03*
X43500Y317100D03*
X48420Y321616D03*
X44200Y332000D03*
X44525Y324000D03*
X39100Y321600D03*
X35500Y340500D03*
Y335000D03*
X44220Y341008D03*
X44500Y344000D03*
Y355500D03*
X37400Y359900D03*
X44500Y348000D03*
X44525Y360000D03*
X35100Y352400D03*
X44500Y351600D03*
X38200Y364855D03*
X35900Y363025D03*
X37800Y371225D03*
X44525Y364000D03*
Y368000D03*
X37300Y375000D03*
X44525Y376000D03*
X37875Y377925D03*
X44525Y387800D03*
X37735Y391200D03*
X44525Y391650D03*
X35101Y381610D03*
X44525Y384000D03*
X47075Y391730D03*
X44500Y380000D03*
X44490Y397850D03*
X44525Y394150D03*
X36911Y394915D03*
X37067Y398337D03*
X44341Y406480D03*
X44330Y401450D03*
X36600Y408600D03*
X39530Y409100D03*
X42900Y412900D03*
X41200Y429100D03*
X43600Y422800D03*
X42200Y435900D03*
X48050Y436350D03*
X46100Y422800D03*
X40848Y448440D03*
X62218Y3000D03*
X54200Y25400D03*
X53000Y41500D03*
X58976Y36402D03*
X53600Y44100D03*
X56348Y36210D03*
X59425Y53075D03*
X50508Y57459D03*
X50710Y54724D03*
X57500Y75500D03*
X60000D03*
X55000Y76000D03*
X63086Y65762D03*
X52120Y78373D03*
X59240Y67242D03*
X52502Y80978D03*
X53434Y106562D03*
X53400Y102788D03*
X52155Y121218D03*
X60112Y113992D03*
X53267Y109094D03*
X59945Y120630D03*
X60411Y130200D03*
X52237Y129522D03*
X61123Y133070D03*
X52876Y195712D03*
X52410Y190190D03*
X57141Y209341D03*
X59900Y199900D03*
X52050Y208760D03*
X64050Y201010D03*
X58823Y213531D03*
X52000Y230400D03*
X63300Y237600D03*
X51600Y241200D03*
X59850Y235830D03*
X51010Y233570D03*
X49700Y242900D03*
X50567Y238630D03*
X50700Y250400D03*
X62500Y272500D03*
X58654Y290605D03*
X58900Y288075D03*
X54660Y311660D03*
X60561Y314843D03*
X60613Y312012D03*
X64230Y303210D03*
X56600Y320500D03*
Y324300D03*
X63000Y324100D03*
X56600Y318000D03*
X52820Y325200D03*
X60225Y336099D03*
X57400Y345400D03*
X52900Y360000D03*
X52600Y376600D03*
X58035Y370100D03*
X54400Y374700D03*
X55294Y369729D03*
X52475Y364000D03*
X52765Y390200D03*
X59500Y394000D03*
X58620Y408779D03*
X63200Y408600D03*
X52330Y413350D03*
X59097Y433502D03*
X57470Y426544D03*
X51535D03*
X59511Y424477D03*
X60622Y431273D03*
X64122D03*
X56250Y424200D03*
X52750D03*
X56482Y450344D03*
X62600Y450700D03*
X54100Y448600D03*
X56500Y447600D03*
X63563Y460100D03*
X56476D03*
X56482Y456844D03*
Y453344D03*
X63569Y456844D03*
Y453344D03*
X76500Y66500D03*
X65928Y76500D03*
X68500Y66500D03*
X75280Y75704D03*
X72500Y66500D03*
X74757Y89745D03*
Y92745D03*
Y86745D03*
X66830Y122329D03*
X72044Y132312D03*
X71970Y135893D03*
X69195Y135799D03*
X69285Y132321D03*
X67126Y128100D03*
X66874Y130590D03*
X68335Y141369D03*
X68375Y144100D03*
X68434Y149506D03*
X68432Y152147D03*
X70580Y167179D03*
X72300Y159400D03*
X68600Y159160D03*
X76442Y166907D03*
X73550Y166680D03*
X67330Y169267D03*
X68960Y173300D03*
X75284Y180800D03*
X65301Y187762D03*
X67486Y186414D03*
X75300Y183875D03*
X71146Y186489D03*
X71370Y188993D03*
X67386Y191935D03*
X67486Y188977D03*
X74046Y186490D03*
X71600Y200900D03*
X72150Y204810D03*
X76670Y208772D03*
X75000Y214000D03*
X72500D03*
X70453Y222900D03*
X72000Y235925D03*
X70900Y241500D03*
X71100Y233575D03*
X67700Y229725D03*
X65801Y253145D03*
X68990Y257000D03*
X77010Y256645D03*
X65755Y256045D03*
X73011Y246365D03*
X77384Y253769D03*
X68800Y253300D03*
X65800Y260875D03*
X76500Y270700D03*
X74000Y270800D03*
X68990Y260465D03*
X76284Y280470D03*
X77900Y274700D03*
X70000Y280000D03*
X78600Y283970D03*
X75960Y284049D03*
X65100Y282475D03*
X72700Y301200D03*
X75870Y290700D03*
X78770Y290708D03*
X75300Y305150D03*
X69500Y308700D03*
X64567Y306665D03*
X73400Y313700D03*
X73000Y323400D03*
X68500Y325100D03*
X76900Y323000D03*
X76500Y325500D03*
X78700Y340000D03*
X71000Y394400D03*
X67900Y400525D03*
X69057Y419700D03*
X77860Y408678D03*
X77592Y413437D03*
X66319Y413492D03*
X67000Y408800D03*
X69700D03*
X78800Y423800D03*
X66297Y433002D03*
X71035Y426543D03*
X76770D03*
X69030Y422653D03*
X68100Y425400D03*
X71200Y431700D03*
X72150Y424199D03*
X75650D03*
X77600Y431400D03*
X79010Y445750D03*
X72800Y437900D03*
X70650Y460100D03*
X77500D03*
X82218Y3000D03*
X91700Y66500D03*
X86500Y75000D03*
X88000Y66500D03*
X84500D03*
X90151Y68985D03*
X91358Y89745D03*
Y92745D03*
Y86745D03*
X86700Y119100D03*
X92500Y116200D03*
X89256Y135056D03*
X86100Y153340D03*
X89170Y141540D03*
X89200Y138800D03*
X86100Y155840D03*
X83410Y161020D03*
X86100Y158390D03*
X83520Y158520D03*
X81800Y188500D03*
X80788Y190812D03*
X82370Y197010D03*
X90900Y222850D03*
X81600Y241500D03*
X91300Y252900D03*
X80300Y243700D03*
X80270Y247830D03*
X84000Y261375D03*
X90800Y258225D03*
X83500Y266900D03*
X84016Y258230D03*
X91500Y267000D03*
X85672Y283985D03*
X81864Y297900D03*
X85600Y298100D03*
X90923Y293520D03*
X82200Y308700D03*
X82022Y303350D03*
X84126Y311790D03*
X79600Y312000D03*
X85500Y323400D03*
Y326700D03*
X93288Y330289D03*
X85600Y335000D03*
X81900Y337100D03*
X81700Y342600D03*
X86300Y397600D03*
X90500D03*
X82500D03*
X89487Y408435D03*
X87600Y414500D03*
X87800Y410300D03*
X84801Y409760D03*
X92500Y408630D03*
X86481Y407871D03*
X81552Y409660D03*
X93259Y424200D03*
X88565Y426535D03*
X79600Y426400D03*
X92001Y450402D03*
X82256Y445577D03*
X85276Y445550D03*
X81990Y448085D03*
X85490D03*
X92870Y437831D03*
X89700Y437900D03*
X84823Y460100D03*
X91909Y458275D03*
X92801Y452793D03*
X102218Y3000D03*
X107000Y44500D03*
X104575Y62369D03*
X102190Y63225D03*
X104600Y50501D03*
X104575Y67581D03*
X95400Y66500D03*
X98000Y75500D03*
X98500Y66500D03*
X102190Y66725D03*
X107124Y71004D03*
X108800Y91900D03*
X104425Y82500D03*
X106000Y91900D03*
X108727Y99153D03*
X100000Y98500D03*
X105916Y109952D03*
X100360Y116500D03*
X101230Y127010D03*
X96400Y137475D03*
X102999Y131799D03*
X108270Y138630D03*
X95950Y152900D03*
X95944Y149687D03*
X103500Y240619D03*
X95300Y247100D03*
X97177Y263320D03*
X102600Y267000D03*
X107200Y265000D03*
X106800Y262076D03*
X97440Y283590D03*
X106100Y282900D03*
X100700Y293600D03*
X108551Y294241D03*
X99990Y311200D03*
X105000Y311900D03*
X105100Y309300D03*
X94400Y311100D03*
Y307200D03*
X96457Y323194D03*
X105755Y327719D03*
X103000Y323800D03*
X95060Y327625D03*
X106852Y323292D03*
X97800Y325700D03*
X97608Y335534D03*
X99026Y338368D03*
X103180Y336286D03*
X108108Y395100D03*
X103400Y420000D03*
X95280Y412500D03*
X98100Y412400D03*
X105500Y418200D03*
X100457Y409100D03*
X98300Y407600D03*
X108500Y408680D03*
X104112Y422946D03*
X95845Y424755D03*
X97156Y450437D03*
X94560Y443287D03*
X100225Y443127D03*
X106700Y447730D03*
X95770Y437920D03*
X95870Y445483D03*
X99370D03*
X103900Y447640D03*
X98996Y458275D03*
X106083D03*
X96301Y452793D03*
X122218Y3000D03*
X111000Y44600D03*
X119000D03*
X115000Y44500D03*
X122500Y58000D03*
X118500Y75500D03*
X116500Y74000D03*
X109121Y69500D03*
X119700Y89200D03*
X116560Y88651D03*
X123710Y82300D03*
X123740Y79791D03*
X115025Y104800D03*
X120726Y105000D03*
X115200Y98200D03*
X120724Y108937D03*
X120626Y123500D03*
X112000D03*
X116200Y115100D03*
X109350Y115501D03*
X109200Y118500D03*
Y128500D03*
X118990Y131580D03*
X109670Y136060D03*
X118692Y137304D03*
X120800Y147200D03*
X117800D03*
X113000Y160700D03*
X115400Y159500D03*
X113000Y158000D03*
X122156Y157844D03*
X122900Y170100D03*
X123120Y213088D03*
X119060Y199695D03*
X123790Y227656D03*
X118300Y237500D03*
X123690Y230156D03*
X122876Y242800D03*
X117840Y242200D03*
X121200Y234890D03*
X112200Y234520D03*
X116143Y230790D03*
X111400Y254680D03*
X122876Y245300D03*
X120020Y254430D03*
X119105Y251511D03*
X121720Y265330D03*
X117400Y266500D03*
X109800Y264928D03*
X111100Y273700D03*
X120070D03*
X115000D03*
X111177Y293471D03*
X120600D03*
X110565Y296331D03*
X118009Y313810D03*
Y311200D03*
X115535Y335235D03*
X115600Y337900D03*
X114700Y351200D03*
X121200Y359200D03*
X111330Y357800D03*
X120200Y361600D03*
X114700Y348500D03*
X111460Y361770D03*
X115000Y369500D03*
X111869Y365454D03*
X121175Y385125D03*
X110900Y378500D03*
X123100Y390600D03*
X119200Y406175D03*
X122600Y394600D03*
X119026Y393332D03*
X119791Y412301D03*
X113000Y416200D03*
X119500Y433600D03*
X111510Y434710D03*
X121700Y424005D03*
X123170Y433200D03*
X127900Y45000D03*
X129575Y57375D03*
X126425Y57000D03*
X133000Y59900D03*
X130500Y74700D03*
X129300Y82650D03*
X131470Y81260D03*
X129500Y91475D03*
X129328Y122500D03*
X126575Y111416D03*
X131528Y114271D03*
X135500Y138000D03*
Y135000D03*
X134400Y127652D03*
X131700Y131000D03*
X132828Y138400D03*
X133500Y146800D03*
X138458Y146458D03*
X133500Y149385D03*
X124500Y167100D03*
X126500Y158000D03*
X133690Y158100D03*
X136190D03*
X126300Y176575D03*
X126500Y174000D03*
X137900Y179160D03*
X125700Y183700D03*
X129810Y191310D03*
X135000Y206900D03*
X124338Y204742D03*
X124779Y201633D03*
X126153Y199079D03*
X135000Y221200D03*
X132500Y221900D03*
X138100Y213600D03*
X124226Y225194D03*
X134358Y230069D03*
X130167Y234733D03*
X128900Y255898D03*
X133000Y256100D03*
X128760Y265726D03*
X127600Y259700D03*
X131216Y280187D03*
X135315Y279813D03*
X125100Y273720D03*
X128760Y273701D03*
X137083Y278045D03*
X137196Y274491D03*
X132420Y273811D03*
X138600Y295900D03*
X124016Y313784D03*
X135462Y313727D03*
X124100Y311100D03*
X129800Y325800D03*
X138590Y345710D03*
X124400Y345300D03*
X125910Y335006D03*
X125900Y337600D03*
X133300Y334100D03*
X136000Y341000D03*
X133100Y358900D03*
X133000Y361500D03*
X132600Y350090D03*
X124350Y352450D03*
X129776Y374500D03*
X138700Y376600D03*
X133640Y390524D03*
X126340Y382700D03*
X125174Y393916D03*
X124287Y406262D03*
X127300Y392600D03*
X135300Y399900D03*
X137900Y399500D03*
X131540Y394690D03*
X132700Y402700D03*
X129900Y415583D03*
X133500Y409110D03*
X133070Y420874D03*
X134300Y416414D03*
X136230Y423935D03*
X124500Y424005D03*
X132070Y433110D03*
X133572Y423935D03*
X125930Y433110D03*
X138750Y451500D03*
X138500Y457250D03*
X138750Y454500D03*
X142218Y3000D03*
X147947Y9800D03*
X146800Y79000D03*
X140869Y89055D03*
X145000Y90700D03*
X142400Y91300D03*
X141100Y86500D03*
X141700Y96929D03*
X140869Y104803D03*
Y120551D03*
Y112677D03*
X148819Y123197D03*
X143400Y121700D03*
X141220Y123070D03*
X147600Y117000D03*
X151800Y116500D03*
X152800Y111600D03*
X148819Y125697D03*
X149800Y138100D03*
X145185Y134214D03*
X142892Y136645D03*
X142000Y146000D03*
X143269Y150456D03*
X150155Y145086D03*
X152556Y147683D03*
X148400Y155765D03*
X146300Y161010D03*
X153134Y178572D03*
X140554Y168887D03*
X153200Y170990D03*
X140554Y171688D03*
X150619Y178646D03*
X145296Y188835D03*
X140830Y192530D03*
X153051Y187354D03*
X150005Y184973D03*
X149100Y189963D03*
X144280Y195130D03*
X151940Y203710D03*
X151900Y213200D03*
X143980Y199674D03*
X147800Y200789D03*
X140903Y199421D03*
X152500Y199500D03*
X146390Y224040D03*
X146000Y216350D03*
X141954Y224274D03*
X142300Y216300D03*
X145500Y227700D03*
X153100Y234800D03*
X142085Y230549D03*
X151040Y237870D03*
X145580Y248082D03*
X141280Y256310D03*
X142780Y266830D03*
X149215Y267745D03*
X152400Y284400D03*
X150240Y277940D03*
X152400Y293400D03*
X152500Y289425D03*
X150293Y302117D03*
X147500Y289405D03*
X150293Y315493D03*
X151320Y322700D03*
X142500Y345800D03*
X148600Y336300D03*
X142202Y334000D03*
X142300Y336700D03*
X144800D03*
X144700Y334100D03*
X153419Y341978D03*
X143945Y354146D03*
X148316Y359086D03*
X141045Y355309D03*
X150900Y360325D03*
X151695Y357900D03*
X149500Y356700D03*
X141000Y358500D03*
X140700Y370252D03*
X139200Y372510D03*
X149000Y383070D03*
X152100Y378400D03*
X143300Y396400D03*
X140300Y395100D03*
X141520Y399700D03*
X139400Y392460D03*
X151265Y399500D03*
X142511Y393690D03*
X146600Y410600D03*
X153079Y412000D03*
X149600Y410500D03*
X139700Y415100D03*
X150000Y414750D03*
X143000Y414600D03*
X140600Y412300D03*
X152100Y425700D03*
X145365Y426050D03*
X148060Y423500D03*
X148100Y433400D03*
X152200Y423100D03*
X148041Y426700D03*
X138987Y423935D03*
X151398Y449930D03*
X149041Y458750D03*
X162218Y3000D03*
X165700Y11100D03*
X166719Y75874D03*
X158246Y78872D03*
X168297Y93976D03*
X164429Y93991D03*
X158873Y93976D03*
X166500Y96400D03*
X163423Y96281D03*
X159923D03*
X166200Y105500D03*
X158420Y116610D03*
X159700Y112000D03*
X155530Y116640D03*
X156200Y111600D03*
X162657Y117297D03*
X154050Y137100D03*
X159000Y135000D03*
X166700Y132360D03*
X156406Y129203D03*
X162419Y131032D03*
X155325Y139440D03*
X153954Y145086D03*
X161900Y150500D03*
X165690Y149622D03*
X156481Y155933D03*
X162200Y158200D03*
X159900Y155600D03*
X161240Y177820D03*
X161237Y181735D03*
Y185815D03*
X161240Y190477D03*
X166361Y209794D03*
X156467Y203500D03*
X162594Y212585D03*
Y210085D03*
X166140Y205955D03*
X165381Y201274D03*
X166308Y225189D03*
X153744Y217435D03*
X153800Y214900D03*
X162653Y218843D03*
X159643Y226484D03*
X162200Y221376D03*
X163500Y229184D03*
X167200Y222600D03*
X155800Y234700D03*
X161200Y233600D03*
X165500Y236100D03*
X157200Y240000D03*
X156970Y255000D03*
X165013Y254986D03*
X160973D03*
X164500Y266000D03*
X163690Y268610D03*
X160590Y263300D03*
X156970Y263250D03*
X164800Y263300D03*
X158750Y284949D03*
X168392Y298493D03*
X168300Y301100D03*
X162100Y291600D03*
X161400Y307600D03*
X162160Y313560D03*
X164500Y314800D03*
X155000Y321100D03*
X164790Y341100D03*
X168557Y341221D03*
X158459Y340898D03*
X158467Y344067D03*
X163800Y356800D03*
X161300Y354600D03*
X164318Y389102D03*
X157282D03*
X156900Y385700D03*
X154500Y387350D03*
X159050Y387334D03*
X162550D03*
X165500Y386000D03*
X155452Y401000D03*
X154000Y414750D03*
X160540Y416912D03*
X165194Y428688D03*
X157294Y435623D03*
X167008Y430718D03*
X167865Y427771D03*
X163700Y422119D03*
X159396Y449408D03*
X160700Y445550D03*
X158100Y442700D03*
X160852Y460118D03*
X168029Y456660D03*
X157500Y453390D03*
X182218Y3000D03*
X176900Y14625D03*
X178200Y76145D03*
X175700Y76245D03*
X173853Y93991D03*
X182925Y84300D03*
X179900Y91300D03*
X181960Y99260D03*
X169700Y102250D03*
X176300Y98700D03*
X172847Y96281D03*
X169347D03*
X180333Y114292D03*
X179500Y116800D03*
X182000Y117200D03*
X171600Y114000D03*
X182865Y113706D03*
X174600Y114000D03*
X169100Y113900D03*
X182103Y132294D03*
X170867Y128211D03*
X178290Y128824D03*
X176550Y125210D03*
X178284Y132394D03*
X170610Y131900D03*
X174436Y132394D03*
X168800Y126800D03*
X172100Y146300D03*
X176000Y140500D03*
X172890Y153260D03*
X171700Y156900D03*
X169500Y180200D03*
X170800Y193100D03*
X172621Y208300D03*
X173800Y225400D03*
X170400Y214700D03*
X172400Y220700D03*
X175300Y240000D03*
X174400Y249136D03*
Y254736D03*
X179846Y255150D03*
X176900Y270100D03*
X174292Y263300D03*
X171592Y263312D03*
X168710Y272256D03*
X172977Y277000D03*
X182435Y281797D03*
X179217Y278528D03*
X168656Y275156D03*
X181194Y294074D03*
X182232Y296424D03*
X173880Y312430D03*
X174232Y304333D03*
X176563Y310917D03*
X176533Y314049D03*
X170550Y304050D03*
X169077Y308677D03*
X170561Y306631D03*
X182372Y325961D03*
X181050Y332250D03*
X171098Y341224D03*
X182700Y342216D03*
X169200Y349400D03*
X180600Y360200D03*
X180350Y368650D03*
X177500Y369100D03*
X177082Y387402D03*
X178850Y385634D03*
X182350D03*
X169669Y399419D03*
X172550Y398690D03*
X172530Y420950D03*
X182750Y426750D03*
X172530Y429470D03*
X171400Y450600D03*
X189400Y69600D03*
X187272Y84472D03*
X191312Y84512D03*
X190200Y100500D03*
X198281Y101286D03*
X184800Y100300D03*
X187700Y99000D03*
X187400Y101500D03*
X190800Y117200D03*
X193096Y115600D03*
X190744Y114456D03*
X187069Y116800D03*
X184729Y115820D03*
X187360Y132425D03*
X195983Y132294D03*
X191482Y129294D03*
X186200Y125600D03*
X184000Y140500D03*
X196577Y141185D03*
X189300Y148400D03*
X189700Y140400D03*
X196827Y240349D03*
X191693Y236370D03*
X185897Y249936D03*
X196240Y253430D03*
X193084Y257400D03*
X194567Y255288D03*
X187400Y255700D03*
X191583Y261363D03*
X190900Y271700D03*
X193386Y269142D03*
X184200Y264900D03*
X185000Y270700D03*
X189228Y280655D03*
X195370Y273297D03*
X183625Y273500D03*
X196200Y278200D03*
X196100Y281820D03*
X187623Y297475D03*
X192380Y291900D03*
X196443Y294065D03*
X191199Y300200D03*
X185725Y307320D03*
X192448Y308314D03*
X195031Y307182D03*
X194600Y313300D03*
X197853Y307200D03*
X197155Y314223D03*
X188546Y326356D03*
X190465Y344426D03*
X190600Y337900D03*
X183800Y345400D03*
X197775Y346617D03*
X194800Y341700D03*
X191408Y357451D03*
X197450Y356560D03*
X190922Y350990D03*
X196050Y358770D03*
X191420Y354710D03*
X190965Y348090D03*
X197711Y349250D03*
X195000Y373900D03*
X197400Y367600D03*
Y370250D03*
X184118Y387402D03*
X197620Y385425D03*
X190050Y389140D03*
X190100Y392270D03*
X191843Y403995D03*
X189054Y397500D03*
X194500Y402600D03*
X200274Y410960D03*
X185875Y415051D03*
X185245Y417500D03*
X195000Y422540D03*
X190270Y409962D03*
X189762Y429177D03*
X189766Y432050D03*
X189838Y434910D03*
X186720Y432490D03*
X186300Y448700D03*
X185000Y451500D03*
X189600Y459800D03*
X185000Y454000D03*
Y456500D03*
X191780Y453300D03*
Y456700D03*
X202218Y3000D03*
X207700Y59100D03*
X211400Y59238D03*
X204300Y60600D03*
X201500Y61000D03*
X209142Y53664D03*
X213100Y69300D03*
X209500Y92326D03*
X211800Y93870D03*
X201900Y83300D03*
X209824Y106122D03*
X203600Y117000D03*
X199940Y117500D03*
X211370Y117000D03*
X208200Y111760D03*
X203970Y125500D03*
X199985Y132294D03*
X212757Y127064D03*
X212727Y129654D03*
X208627Y132394D03*
X208576Y128957D03*
X204120Y132294D03*
X200000Y128764D03*
X208500Y126057D03*
X212727Y132154D03*
X211200Y140513D03*
X205598Y140480D03*
X203542Y213254D03*
X206200Y255385D03*
X198990Y247811D03*
X200680Y257540D03*
X206051Y247911D03*
X211265Y267300D03*
X205500Y258300D03*
X201100Y265120D03*
X214034Y261482D03*
X201000Y262500D03*
X203090Y269229D03*
X205590Y269129D03*
X205900Y266130D03*
X205130Y282000D03*
X204207Y278200D03*
X204258Y286691D03*
X213258Y273265D03*
X207220Y301180D03*
X204560Y301130D03*
X212911Y293869D03*
X206430Y298780D03*
X199729Y314565D03*
X198672Y318175D03*
X208628Y324665D03*
X200300Y328800D03*
X207750Y366500D03*
X208000Y373240D03*
X200222Y398150D03*
X213200Y399166D03*
X199880Y402846D03*
X203180Y416371D03*
X207539Y408686D03*
X200000Y407040D03*
X207278Y416022D03*
X198600Y426600D03*
X202513Y434800D03*
X198405D03*
X211865Y444520D03*
X199000Y444500D03*
X205200Y445400D03*
X213225Y442220D03*
X200000Y455800D03*
X209300Y457700D03*
X222218Y3000D03*
X214306Y62233D03*
X229900Y61000D03*
X227547Y74275D03*
X219600Y74000D03*
X215800Y69300D03*
X218600D03*
Y92100D03*
X221300D03*
X224330Y83210D03*
X227760Y82524D03*
X224958Y107236D03*
X219900Y101300D03*
X222890Y101240D03*
X215294Y117094D03*
X226887Y117297D03*
X223300Y117400D03*
X221500Y125100D03*
X217262Y129294D03*
X225284Y132294D03*
Y129294D03*
X217262Y132294D03*
X221278D03*
X225300Y125200D03*
X219600Y147000D03*
X227700Y151900D03*
X221000Y243000D03*
X220100Y237200D03*
X223800Y254800D03*
X227316Y256700D03*
X215100Y244100D03*
X215500Y247111D03*
X216800Y255550D03*
X215510Y253310D03*
X225275Y246000D03*
X217500Y264000D03*
X219900Y267100D03*
X220866Y272160D03*
X227232Y270539D03*
X226405Y266335D03*
X222833Y261668D03*
X225441Y282267D03*
X219722Y286728D03*
X227841Y275773D03*
X219339Y284138D03*
X219359Y281580D03*
X226500Y273000D03*
X229220Y283250D03*
X223672Y290735D03*
X223646Y293960D03*
X215600Y316800D03*
X213610Y308800D03*
X214400Y303997D03*
X226100Y325065D03*
X217300Y322800D03*
X225867Y345033D03*
X225650Y337520D03*
X221000Y343800D03*
X216405Y335970D03*
X214175Y333740D03*
X228230Y340040D03*
X221000Y352000D03*
X223160Y362600D03*
X224632Y369825D03*
X225700Y362500D03*
X213490Y373690D03*
X226710Y364815D03*
X223420Y367080D03*
X220515Y384900D03*
X217390Y401340D03*
X222986Y400323D03*
X222225Y407650D03*
X216725D03*
X219050Y418850D03*
X217725Y410150D03*
X221225D03*
X226830Y435170D03*
X225000Y433100D03*
X219250Y422150D03*
X213900Y436000D03*
X217100Y436100D03*
X218085Y444520D03*
X224000Y449100D03*
X216725Y442220D03*
X222200Y458700D03*
X215000Y458600D03*
X242218Y3000D03*
X233000Y47100D03*
X237000Y47200D03*
X230800Y57613D03*
X234537Y74638D03*
X239347Y79457D03*
X230600Y91700D03*
X239660Y91920D03*
X232150Y82480D03*
X237280Y107510D03*
X229000Y101000D03*
X240160Y107000D03*
X240710Y99570D03*
X232325Y101230D03*
X236648Y100739D03*
X242812Y117501D03*
X238900Y114800D03*
X234500Y117500D03*
X230293Y117417D03*
X239900Y117550D03*
X239206Y112300D03*
X242800Y132200D03*
X231100Y125600D03*
X233511Y132594D03*
X234900Y126100D03*
X229396Y132294D03*
X233511Y129594D03*
X242195Y141003D03*
X230535Y244564D03*
X237700Y257387D03*
X237730Y248085D03*
X242690Y255300D03*
X230000Y255700D03*
X232773Y269532D03*
X232300Y261200D03*
X242940Y268500D03*
X233033Y266483D03*
X229630Y264404D03*
X242087Y271427D03*
X238531Y263081D03*
X231900Y272700D03*
X241188Y279347D03*
X234500Y293500D03*
X242700Y306800D03*
X228800Y302700D03*
X240500Y316575D03*
X236688Y311217D03*
X238400Y304200D03*
X228800Y305500D03*
X235400Y303800D03*
X241400Y328100D03*
X242592Y330683D03*
X243010Y323400D03*
X230445Y325945D03*
X233468Y341046D03*
X235000Y335300D03*
X231689Y334896D03*
X233500Y346911D03*
Y343911D03*
X233300Y356890D03*
X231500Y352500D03*
X233650Y359628D03*
X233800Y354300D03*
X233600Y371500D03*
X230287Y373100D03*
X233800Y390118D03*
X228230Y390390D03*
X232470Y382280D03*
X233600Y377300D03*
X233790Y384490D03*
X239750Y394970D03*
X236670Y394550D03*
X241231Y407285D03*
X236860Y407300D03*
X229900Y436600D03*
X236900Y440565D03*
X239500Y447750D03*
X235400Y451600D03*
X231250Y447000D03*
X235200Y449100D03*
X231400Y449500D03*
X241436Y445784D03*
X240200Y450650D03*
X228200Y459100D03*
X236221Y454400D03*
X240010Y456000D03*
X240210Y453400D03*
X231400Y452000D03*
X248359Y46559D03*
X252925Y54000D03*
X249475Y55812D03*
X248700Y75900D03*
X255750Y77350D03*
X246200Y74600D03*
X253000Y77500D03*
X250000Y73000D03*
X250900Y90900D03*
X255000Y82700D03*
X257800Y82800D03*
X256900Y87300D03*
X251200Y93800D03*
X254397Y103697D03*
X244987Y103528D03*
X251113Y102919D03*
X252300Y107664D03*
X245391Y99589D03*
X251900Y100100D03*
X255213Y106099D03*
X249988Y105792D03*
X246488D03*
X244208Y97302D03*
X247200Y117400D03*
X253100Y119900D03*
X245310Y113910D03*
X252374Y132159D03*
X245500Y127800D03*
X245520Y130600D03*
X251354Y152877D03*
X249300Y237600D03*
X247689Y247929D03*
X253110Y254909D03*
X252639Y247885D03*
X256700Y263800D03*
X255700Y260000D03*
X247470Y269990D03*
X253388Y273655D03*
X250288Y273581D03*
X251459Y286542D03*
Y283542D03*
X257145Y279700D03*
X246200Y299700D03*
X246514Y294325D03*
Y296825D03*
X254355Y300577D03*
X247923Y316400D03*
X257900Y312100D03*
X248900Y304900D03*
X247923Y319000D03*
X253320Y323327D03*
X243750Y369730D03*
X243700Y372730D03*
X244790Y375910D03*
X243410Y381323D03*
X248800Y385700D03*
X249400Y410300D03*
X252350Y412850D03*
X257810Y435100D03*
X245300Y445800D03*
X246700Y451500D03*
X246500Y448500D03*
X243375Y448375D03*
X246700Y454100D03*
X262218Y3000D03*
X267022Y12166D03*
X269095Y34625D03*
X260970Y42441D03*
X259000Y47500D03*
X268500Y45500D03*
X268675Y74400D03*
X267168Y93768D03*
X260132D03*
X259894Y90072D03*
X263102Y91725D03*
X260050Y87026D03*
X259759Y103651D03*
X259500Y101100D03*
X265801Y106040D03*
X260970Y98600D03*
X258713Y106099D03*
X264989Y101732D03*
X268435Y121476D03*
X271602Y121400D03*
X269561Y130987D03*
X271300Y132900D03*
X269493Y138604D03*
X260200Y132395D03*
X260388Y125001D03*
X263294Y153366D03*
X263030Y150846D03*
X268442Y153299D03*
X265942D03*
Y150799D03*
X268442D03*
X269004Y144450D03*
Y141950D03*
X269133Y164982D03*
X265226D03*
X268339Y222126D03*
X272300Y251000D03*
X258628Y247600D03*
X258475Y254872D03*
X267100Y265000D03*
X269016Y266991D03*
X259500Y263700D03*
X262730Y267600D03*
X258000Y266300D03*
X266600Y268700D03*
X262700Y265100D03*
X258000Y284900D03*
X262100Y280700D03*
X266200Y300500D03*
X266250Y297900D03*
X266200Y294800D03*
X261500Y290440D03*
X266300Y307500D03*
X264265Y315817D03*
X262930Y325300D03*
X259420Y345930D03*
X271100Y346575D03*
X259420Y343230D03*
Y340630D03*
X265922Y354238D03*
X273580Y354250D03*
X271990Y362360D03*
X272100Y396300D03*
X265320Y392290D03*
X265100Y395100D03*
X272400Y392400D03*
X265100Y424000D03*
X266300Y435900D03*
X271500Y446800D03*
X271710Y449840D03*
X266727Y443185D03*
X261700Y439700D03*
X265130Y440070D03*
X261100Y443500D03*
X269534Y459061D03*
X269561Y456044D03*
X282218Y3000D03*
X277000Y41982D03*
X282440Y51941D03*
X274219Y51641D03*
X277000Y51665D03*
X274500Y58000D03*
X279934Y51688D03*
X286000Y67975D03*
X279800Y72700D03*
X274400Y90019D03*
X273400Y92800D03*
X276400Y92300D03*
X287578Y84092D03*
X283500Y89500D03*
X278300Y95019D03*
X274760Y105140D03*
X275386Y102710D03*
X280910Y102880D03*
X279200Y114100D03*
X285250Y117250D03*
X274200Y109500D03*
X274500Y131629D03*
X279600Y131400D03*
X283500Y126000D03*
X275960Y126010D03*
X273450Y125050D03*
X280744Y142070D03*
X283248Y142046D03*
X280616Y150971D03*
X283616D03*
X287555Y142419D03*
X285899Y153542D03*
X283399D03*
X278155Y176085D03*
X279457Y171318D03*
X286000Y242100D03*
X279983Y235254D03*
X282483D03*
X283974Y251372D03*
X286800Y251400D03*
X276200Y251500D03*
X280082Y251328D03*
X280030Y267098D03*
Y264098D03*
X284357Y264027D03*
X285911Y269899D03*
X281889D03*
X287755Y287538D03*
X281889Y287636D03*
X282911Y279569D03*
X285911D03*
X281300Y308800D03*
X287050Y305850D03*
X276660Y316900D03*
X276155Y329999D03*
X273355Y330001D03*
X286372Y320700D03*
X285860Y336131D03*
X277500Y348469D03*
X275520Y357910D03*
X277290Y355820D03*
X277572Y351198D03*
X276100Y375900D03*
X287725Y363473D03*
X287761Y366200D03*
X287500Y376900D03*
X276145Y366455D03*
X276400Y370400D03*
X276100Y381500D03*
X284614Y387136D03*
X283664Y379236D03*
X273100Y381500D03*
X285191Y390840D03*
X287630Y389378D03*
X275700Y403500D03*
X277700Y406100D03*
X287476Y396680D03*
X281300Y419300D03*
X278200Y408700D03*
X287500Y416100D03*
X278409Y433722D03*
X276400Y431810D03*
X275100Y427682D03*
X274619Y424725D03*
X283622Y447155D03*
X275138Y451215D03*
X276632Y439502D03*
X283674Y449975D03*
X277563Y460028D03*
X283707Y459398D03*
X283715Y452769D03*
X302218Y3000D03*
X300600Y10591D03*
X288856Y12166D03*
X295402Y48051D03*
X290245Y46978D03*
X300425Y54516D03*
X290000Y67975D03*
X293773Y73530D03*
X300070Y84000D03*
X300856Y104059D03*
X301151Y108649D03*
X294600Y106900D03*
X298575Y101900D03*
X294800Y111800D03*
X298975Y118900D03*
X301000Y121016D03*
X295075Y119100D03*
X301936Y135797D03*
X294200Y128800D03*
X301000Y129900D03*
X290200Y129500D03*
X293693Y152232D03*
X290889Y152318D03*
X298005Y151118D03*
Y148618D03*
Y146118D03*
X292204Y142610D03*
X301936Y143897D03*
X301507Y195435D03*
X301120Y226421D03*
X296734Y216079D03*
X301120Y229810D03*
X290586Y234844D03*
X288086D03*
X301120Y235626D03*
Y238765D03*
X299138Y244513D03*
X302687Y275497D03*
X291500Y287670D03*
Y285170D03*
X298840Y279640D03*
X291300Y315900D03*
X296938Y325700D03*
X301500Y326500D03*
X290120Y339370D03*
X290000Y335600D03*
X300700Y341300D03*
X295500Y354920D03*
X296780Y371500D03*
X298748Y390118D03*
X297399Y397382D03*
X290800Y438300D03*
X291623Y447747D03*
X291703Y450819D03*
X291689Y453912D03*
Y456912D03*
Y459912D03*
X295729Y453912D03*
Y456912D03*
Y459912D03*
X297738Y452418D03*
Y458418D03*
Y455418D03*
X313977Y33400D03*
X303575Y54516D03*
X316025Y60200D03*
X309570Y84000D03*
X316066Y108407D03*
X307400Y122300D03*
X304436Y135897D03*
X307500Y125635D03*
X315900Y125900D03*
X313800Y124300D03*
X307560Y128500D03*
X305936Y143897D03*
X309936D03*
X313936D03*
X307487Y219503D03*
X304987D03*
X310449Y218617D03*
X317110Y219140D03*
X309521Y229786D03*
Y238741D03*
X307500Y256500D03*
X305000Y252400D03*
X307600Y252300D03*
X307800Y259200D03*
X302800Y286200D03*
X311670Y285160D03*
X302879Y282487D03*
Y279686D03*
X309700Y294789D03*
X315810Y293450D03*
X312315Y293207D03*
X317430Y295665D03*
X314820Y296128D03*
X314201Y302361D03*
X314180Y299440D03*
X303077Y297519D03*
X306500Y301500D03*
X314132Y310178D03*
X314170Y307020D03*
X309500Y315000D03*
X304000Y305000D03*
X303000Y309200D03*
X311000Y320500D03*
X312300Y340700D03*
X315075Y366500D03*
X308906Y362637D03*
X314340Y373296D03*
X311925Y366475D03*
X312226Y382766D03*
X308500Y382100D03*
X314985Y397639D03*
Y394639D03*
X314969Y456527D03*
X322218Y3000D03*
X319175Y60200D03*
X321800Y60055D03*
X322600Y76100D03*
X322500Y102900D03*
X331881Y108593D03*
Y104577D03*
X320500Y100400D03*
X331881Y112608D03*
X324011Y118843D03*
X324023Y121943D03*
Y115643D03*
X320765Y114582D03*
X318000Y117200D03*
X329297Y134594D03*
Y129890D03*
X321276Y134532D03*
X321349Y130044D03*
X331741Y138243D03*
Y125796D03*
X320239Y151075D03*
X317936Y143897D03*
X323509Y153377D03*
X329005Y152657D03*
X328087Y141608D03*
X321600Y142100D03*
X323384Y157378D03*
X331405Y157411D03*
X323384Y165378D03*
Y161378D03*
X331405Y164911D03*
Y159911D03*
Y154911D03*
Y167411D03*
X323384Y169378D03*
Y173378D03*
Y177378D03*
X331405Y177411D03*
Y179911D03*
Y174911D03*
Y169911D03*
Y182926D03*
Y172411D03*
Y187411D03*
Y192411D03*
Y189911D03*
X320054Y195163D03*
X319601Y201140D03*
X326932Y205685D03*
X326733Y209885D03*
X321045Y210257D03*
X320937Y212839D03*
X326733Y201485D03*
X320054Y198663D03*
X326323Y226349D03*
X317922Y226373D03*
X326731Y213648D03*
X320931Y215387D03*
X326323Y229738D03*
X317922Y229762D03*
Y238717D03*
Y235328D03*
X326323Y235304D03*
Y238693D03*
X327162Y278972D03*
X317670Y291430D03*
X330900Y314700D03*
X325007Y328608D03*
Y326008D03*
X327704Y328635D03*
Y326035D03*
X325007Y323508D03*
X327704Y323535D03*
X325038Y356890D03*
X329925Y356016D03*
X325320Y390118D03*
X325200Y383900D03*
X331500Y383300D03*
X332470Y397092D03*
Y394092D03*
X325593Y406500D03*
X329093D03*
X318593D03*
X322093D03*
X331646Y466536D03*
X342218Y3000D03*
X337375Y76600D03*
X342900Y66100D03*
X339900Y69100D03*
Y66000D03*
X339908Y104577D03*
Y108593D03*
X342200Y100500D03*
X342180Y106900D03*
X339101Y121128D03*
X339908Y112609D03*
X333278Y151129D03*
X339369Y151952D03*
X339800Y154911D03*
Y159911D03*
Y165911D03*
X339939Y162911D03*
X339800Y169911D03*
Y176911D03*
Y179911D03*
X339812Y173380D03*
X339800Y182926D03*
Y185911D03*
Y189911D03*
X337083Y197000D03*
X337400Y193449D03*
X337004Y202113D03*
Y206113D03*
Y210113D03*
X334723Y226349D03*
Y229738D03*
X334724Y238669D03*
Y235280D03*
X337467Y236984D03*
X336312Y286352D03*
X336461Y283202D03*
X340612Y278972D03*
X339700Y295900D03*
Y293000D03*
X347100Y313700D03*
X342604Y318773D03*
X345500Y342690D03*
X335475Y358500D03*
X335700Y376400D03*
X335500Y363200D03*
X335708Y372008D03*
X334600Y383300D03*
X334112Y447668D03*
X351331Y20788D03*
Y40788D03*
Y60788D03*
Y80788D03*
Y100788D03*
Y120788D03*
Y140788D03*
Y160788D03*
Y180788D03*
Y200788D03*
Y220788D03*
Y240788D03*
Y260788D03*
Y280788D03*
Y300788D03*
X349290Y337646D03*
X351331Y357531D03*
Y377531D03*
Y397531D03*
Y417531D03*
Y437531D03*
X373420Y-447134D03*
X370905D03*
Y-443881D03*
X373420D03*
X376346Y-447134D03*
X375904Y-438145D03*
X374975Y-435380D03*
X372211Y-440841D03*
X375964Y-215959D03*
X374666Y-218571D03*
X373480Y-210223D03*
X370965D03*
Y-206970D03*
X376406Y-206985D03*
X373480Y-206970D03*
X372271Y-213263D03*
X375876Y-159873D03*
X372183Y-162569D03*
X373392Y-168862D03*
X370877D03*
Y-165609D03*
X373392D03*
X376318Y-168862D03*
X374947Y-157108D03*
X375964Y12313D03*
X374666Y9701D03*
X373480Y18049D03*
X370965D03*
X372271Y15009D03*
X370965Y21302D03*
X376406Y21287D03*
X373480Y21302D03*
X373420Y59410D03*
X370905D03*
Y62663D03*
X373420D03*
X376346Y59410D03*
X375904Y68399D03*
X374975Y71164D03*
X372211Y65703D03*
X375964Y381585D03*
X374666Y378973D03*
X372271Y384281D03*
X376406Y390559D03*
X373480Y387321D03*
Y390574D03*
X370965Y387321D03*
Y390574D03*
X391993Y-473196D03*
Y-469943D03*
X381788Y-443881D03*
X384303D03*
Y-447134D03*
X378862Y-447119D03*
X381788Y-447134D03*
X379304Y-438145D03*
X380602Y-435533D03*
X382997Y-440841D03*
X379364Y-215959D03*
X380293Y-218724D03*
X383057Y-213263D03*
X381848Y-206970D03*
X384363D03*
Y-210223D03*
X381848D03*
X378922Y-206970D03*
X379276Y-159873D03*
X381760Y-165609D03*
X384275D03*
Y-168862D03*
X378834Y-168847D03*
X381760Y-168862D03*
X382969Y-162569D03*
X380574Y-157261D03*
X392081Y-115285D03*
Y-112032D03*
X391950Y-74043D03*
Y-70790D03*
X379364Y12313D03*
X380293Y9548D03*
X383057Y15009D03*
X384363Y18049D03*
X381848D03*
Y21302D03*
X384363D03*
X378922D03*
X381788Y62663D03*
X384303D03*
Y59410D03*
X378862Y59425D03*
X381788Y59410D03*
X379304Y68399D03*
X380602Y71011D03*
X382997Y65703D03*
X391950Y214106D03*
Y217359D03*
Y255229D03*
Y258482D03*
X379364Y381585D03*
X380293Y378820D03*
X378922Y390574D03*
X381848D03*
Y387321D03*
X384363Y390574D03*
Y387321D03*
X383057Y384281D03*
X391950Y412378D03*
Y415631D03*
X405391Y-473196D03*
X399950Y-473181D03*
X402876Y-473196D03*
X394508D03*
X397434D03*
X396992Y-464207D03*
X400392D03*
X396063Y-461442D03*
X401690Y-461595D03*
X402876Y-469943D03*
X405391D03*
X404085Y-466903D03*
X393299D03*
X394508Y-469943D03*
X397080Y-121021D03*
X400480D03*
X401409Y-123786D03*
X395782Y-123633D03*
X394596Y-115285D03*
X393387Y-118325D03*
X404173D03*
X405479Y-115285D03*
X402964D03*
X397522Y-112047D03*
X394596Y-112032D03*
X402964D03*
X405479D03*
X400038D03*
X399450Y-74028D03*
X394450Y-74043D03*
Y-70790D03*
X396950Y-74043D03*
X405050D03*
X402550D03*
X405050Y-70790D03*
X402550D03*
X393357Y-67750D03*
X403643D03*
X393357Y211066D03*
X403857D03*
X394450Y217359D03*
Y214106D03*
X396950Y217359D03*
X399450Y217344D03*
X402450Y217359D03*
X404950D03*
X402450Y214106D03*
X404950D03*
X394450Y255229D03*
X396950D03*
X399450Y255244D03*
X405050Y255229D03*
X402550D03*
X394450Y258482D03*
X393357Y261522D03*
X405050Y258482D03*
X402550D03*
X403643Y261522D03*
X394450Y415631D03*
Y412378D03*
X396950Y415631D03*
X399450Y415616D03*
X393357Y409338D03*
X402450Y415631D03*
X404950D03*
X402450Y412378D03*
X404950D03*
X403857Y409338D03*
X415550Y-70790D03*
Y-74043D03*
X413050D03*
Y-70790D03*
X410550Y-74043D03*
X408050Y-74028D03*
X414143Y-67750D03*
Y211066D03*
X415550Y214106D03*
Y217359D03*
X413050D03*
Y214106D03*
X410550Y217359D03*
X408050Y217344D03*
X415550Y255229D03*
X413050D03*
X410550D03*
X408050Y255244D03*
X415550Y258482D03*
X413050D03*
X414143Y261522D03*
X415550Y412378D03*
Y415631D03*
X413050D03*
Y412378D03*
X410550Y415631D03*
X408050Y415616D03*
X414143Y409338D03*
G54D30*
X48500Y396276D03*
Y405724D03*
G54D21*
X20083Y105500D03*
X19783Y116200D03*
X48383Y106200D03*
X49983Y376000D03*
Y384000D03*
Y388000D03*
Y380000D03*
X71983Y76500D03*
X69123Y335220D03*
X99983Y360000D03*
Y364000D03*
X116383Y109300D03*
X109008Y341649D03*
X109083Y337700D03*
X117583Y366600D03*
X117502Y362623D03*
X121083Y376800D03*
X135383Y84300D03*
X137083Y195600D03*
X127283Y234800D03*
Y238300D03*
X133983Y277000D03*
X130483Y361500D03*
X152943Y141056D03*
X138683Y250700D03*
X148733Y397500D03*
Y408000D03*
X167704Y157290D03*
X166833Y161150D03*
X166704Y181735D03*
X156503Y175720D03*
X166704Y185952D03*
Y190725D03*
X158691Y189082D03*
Y192582D03*
X160583Y228732D03*
X158208Y232300D03*
X157574Y242629D03*
X166515Y238479D03*
X171913Y212033D03*
X169583Y228400D03*
X172483Y267000D03*
X170417Y281848D03*
X187864Y194343D03*
X189869Y295096D03*
X188183Y300300D03*
X184983Y422800D03*
X212239Y178269D03*
X204471Y172304D03*
X210170Y194450D03*
X210313Y203530D03*
X199281Y217208D03*
X201714Y286781D03*
X209716Y278739D03*
X201983Y300400D03*
X222964Y172340D03*
Y176346D03*
X223260Y181892D03*
X224695Y193882D03*
X226073Y200555D03*
X225827Y210143D03*
X225693Y204555D03*
X218504Y216030D03*
X216739Y286782D03*
Y282756D03*
X225349Y275773D03*
X233983Y71000D03*
X239483Y109760D03*
X241890Y182782D03*
X235937Y194151D03*
X231578Y188938D03*
X240315Y205261D03*
X232691Y207040D03*
X236376Y283911D03*
X229376Y285912D03*
X233336Y275841D03*
Y279853D03*
X229462Y289941D03*
X235283Y306900D03*
X245083Y71900D03*
X256579Y158751D03*
X242942Y194151D03*
X256059Y203097D03*
X253310Y280778D03*
X253283Y359100D03*
Y355200D03*
X271483Y53000D03*
Y57000D03*
X271493Y117366D03*
X281285Y117391D03*
X283613Y175635D03*
X281147Y209511D03*
Y213530D03*
X288527Y165802D03*
X290920Y187914D03*
X293197Y393332D03*
X315883Y122000D03*
X306483Y131290D03*
X304565Y181885D03*
Y185885D03*
X316517Y188372D03*
X314788Y216137D03*
X311483Y373000D03*
X305733Y393352D03*
Y397382D03*
X328913Y159411D03*
X320892Y161378D03*
Y165378D03*
Y157378D03*
X328913Y179411D03*
Y183411D03*
Y187411D03*
Y191411D03*
X321913Y183411D03*
X337398Y104676D03*
Y112708D03*
Y108692D03*
X337308Y186961D03*
G54D12*
X17716Y18465D03*
X45276D03*
X264173Y20040D03*
X291733D03*
X309055Y18465D03*
X336615D03*
G54D13*
X22047Y46417D03*
X333466D03*
G54D40*
X59949Y398551D03*
X64051Y394449D03*
G54D22*
X27660Y106641D03*
Y111759D03*
Y109200D03*
X35140Y106641D03*
Y109200D03*
Y111759D03*
G54D31*
X63898Y24764D03*
X90472D03*
X117047D03*
X211142D03*
X237717D03*
G54D14*
X24016Y89331D03*
X330315D03*
G54D41*
X58839Y465590D03*
X61201D03*
X65925D03*
X73012D03*
X68287D03*
X75374D03*
X80098D03*
X87185D03*
X82461D03*
X89547D03*
X94272D03*
X101358D03*
X108445D03*
X96634D03*
X103721D03*
X115532D03*
X110807D03*
X117894D03*
X144311D03*
X151398D03*
X146673D03*
X158484D03*
X165571D03*
X153760D03*
X160846D03*
X167933D03*
X188445D03*
X190807D03*
X195532D03*
X197894D03*
X202618D03*
X204980D03*
X209705D03*
X212067D03*
X216791D03*
X219154D03*
X223878D03*
X226240D03*
X228602D03*
X230965D03*
X233327D03*
X235689D03*
X271890D03*
X274252D03*
X295512D03*
G54D32*
X53441Y91260D03*
X56000D03*
X58559D03*
Y98740D03*
X53441D03*
G54D23*
X25000Y240500D03*
X32000D03*
X166077Y327640D03*
X162077Y336440D03*
X170077D03*
G54D50*
X90761Y368528D03*
X87611D03*
X92360Y382626D03*
X100539Y378300D03*
X97389D03*
X95510Y382626D03*
G54D33*
X61661Y247701D03*
Y265299D03*
X64220Y247701D03*
X66780D03*
X69339D03*
Y265299D03*
X66780D03*
X64220D03*
G54D42*
X56476Y466378D03*
X63563D03*
X70650D03*
X77736D03*
X84823D03*
X91909D03*
X98996D03*
X106083D03*
X113169D03*
X120256D03*
X139587D03*
X141949D03*
X149035D03*
X156122D03*
X163209D03*
X170295D03*
X186083D03*
X193169D03*
X200256D03*
X207343D03*
X214429D03*
X221516D03*
X238051D03*
X240413D03*
X242776D03*
X245138D03*
X247500D03*
X249862D03*
X267165D03*
X269528D03*
X276614D03*
X278976D03*
X281339D03*
X283701D03*
X286063D03*
X288425D03*
X290787D03*
X293150D03*
X297874D03*
G54D60*
X126610Y377576D03*
X134090D03*
Y387024D03*
X130350D03*
X126610D03*
X256510Y368576D03*
Y378024D03*
X260250Y368576D03*
X263990D03*
Y378024D03*
X260250D03*
G54D15*
X17116Y105500D03*
X16816Y116200D03*
X45416Y106200D03*
X47016Y376000D03*
Y384000D03*
Y388000D03*
Y380000D03*
X69016Y76500D03*
X66156Y335220D03*
X106041Y341649D03*
X106116Y337700D03*
X97016Y360000D03*
Y364000D03*
X113416Y109300D03*
X114616Y366600D03*
X114535Y362623D03*
X118116Y376800D03*
X132416Y84300D03*
X134116Y195600D03*
X124316Y234800D03*
Y238300D03*
X135716Y250700D03*
X131016Y277000D03*
X127516Y361500D03*
X149976Y141056D03*
X145766Y397500D03*
Y408000D03*
X164737Y157290D03*
X163866Y161150D03*
X163737Y181735D03*
X153536Y175720D03*
X163737Y185952D03*
Y190725D03*
X155724Y189082D03*
Y192582D03*
X157616Y228732D03*
X155241Y232300D03*
X154607Y242629D03*
X163548Y238479D03*
X166616Y228400D03*
X167450Y281848D03*
X168946Y212033D03*
X169516Y267000D03*
X182016Y422800D03*
X184897Y194343D03*
X196314Y217208D03*
X186902Y295096D03*
X185216Y300300D03*
X209272Y178269D03*
X201504Y172304D03*
X207203Y194450D03*
X207346Y203530D03*
X198747Y286781D03*
X206749Y278739D03*
X199016Y300400D03*
X219997Y172340D03*
Y176346D03*
X220293Y181892D03*
X221728Y193882D03*
X223106Y200555D03*
X222860Y210143D03*
X222726Y204555D03*
X215537Y216030D03*
X213772Y286782D03*
Y282756D03*
X222382Y275773D03*
X226409Y285912D03*
X226495Y289941D03*
X231016Y71000D03*
X242116Y71900D03*
X236516Y109760D03*
X238923Y182782D03*
X232970Y194151D03*
X239975D03*
X228611Y188938D03*
X237348Y205261D03*
X229724Y207040D03*
X233409Y283911D03*
X230369Y275841D03*
Y279853D03*
X232316Y306900D03*
X253612Y158751D03*
X253092Y203097D03*
X250343Y280778D03*
X250316Y359100D03*
Y355200D03*
X268516Y53000D03*
Y57000D03*
X268526Y117366D03*
X278318Y117391D03*
X285560Y165802D03*
X280646Y175635D03*
X278180Y209511D03*
Y213530D03*
X301598Y181885D03*
Y185885D03*
X287953Y187914D03*
X290230Y393332D03*
X312916Y122000D03*
X303516Y131290D03*
X313550Y188372D03*
X311821Y216137D03*
X308516Y373000D03*
X302766Y393352D03*
Y397382D03*
X325946Y159411D03*
X317925Y161378D03*
Y165378D03*
Y157378D03*
X325946Y179411D03*
Y183411D03*
Y187411D03*
Y191411D03*
X318946Y183411D03*
X334431Y104676D03*
Y112708D03*
Y108692D03*
X334341Y186961D03*
G54D51*
X107936Y390478D03*
X103450Y391450D03*
G54D24*
X23819Y339154D03*
Y349154D03*
Y359154D03*
Y369154D03*
Y379154D03*
Y389154D03*
Y399154D03*
X65709Y52244D03*
X75709Y42244D03*
Y52244D03*
X95709Y42244D03*
X85709D03*
X95709Y52244D03*
X85709D03*
G54D16*
X16800Y112384D03*
X21000Y322484D03*
X48000Y97484D03*
X40400Y420284D03*
X44400D03*
X55500Y72984D03*
X59500D03*
X55500Y81984D03*
X60000Y106484D03*
X61216Y232784D03*
X64500Y71984D03*
X68500D03*
X65216Y232784D03*
X74300Y277584D03*
X66000Y287984D03*
X71900Y309984D03*
X64100Y330984D03*
X76500D03*
X78500Y402984D03*
X74500D03*
X70500D03*
X82500Y71984D03*
X90500Y74984D03*
X88700Y330984D03*
X82500Y402984D03*
X92809Y420814D03*
X88800Y420784D03*
X98500Y72484D03*
X105600Y333684D03*
X101200Y374784D03*
X103800Y384484D03*
X94500Y402984D03*
X102500D03*
X96814Y420814D03*
X115600Y121009D03*
X111600D03*
X120250Y164534D03*
X117400Y419784D03*
X132400Y91384D03*
X129500Y119484D03*
X125500Y120984D03*
X124500Y164534D03*
X127546Y231206D03*
X130000Y402484D03*
X138000Y420234D03*
X128500Y420984D03*
X139500Y143984D03*
X152450Y209278D03*
X148050Y364684D03*
X146000Y420234D03*
X150000D03*
X142000D03*
X155500Y27984D03*
X166733Y122810D03*
X156525Y153186D03*
X156467Y209278D03*
X159164Y223673D03*
X159930Y239094D03*
X160973Y252495D03*
X156963D03*
X165013D03*
X160765Y260447D03*
X156695Y260459D03*
X164801Y260445D03*
X157600Y420284D03*
X153800D03*
X179400Y17684D03*
X169500Y27484D03*
X169000Y77984D03*
X170738Y122810D03*
X178761D03*
X174741D03*
X181541Y213115D03*
X177500Y245584D03*
X173600D03*
X173992Y260315D03*
X169934Y260317D03*
X176700Y349884D03*
X181400Y365784D03*
X177500D03*
X178500Y382684D03*
X182500D03*
X194830Y83044D03*
X185470Y96434D03*
X188980Y96444D03*
X187431Y122971D03*
X191434D03*
X195500Y122984D03*
X196000Y114984D03*
X191000Y137984D03*
X195000D03*
X196332Y146900D03*
X197463Y171972D03*
X187596Y190319D03*
X193724Y189164D03*
X194567Y197581D03*
X188500Y206784D03*
X194485Y238522D03*
X198000Y264134D03*
X193800Y348384D03*
X204000Y122984D03*
X207800D03*
X199500D03*
X211370Y123004D03*
X200000Y114984D03*
X199000Y137884D03*
X207000D03*
X207486Y188953D03*
X199465Y188984D03*
X203476Y188953D03*
X206672Y212368D03*
X210333Y218539D03*
X212100Y250284D03*
X208500Y261884D03*
X201792Y274702D03*
X209811D03*
X205810D03*
X210600Y308184D03*
X227500Y96484D03*
X227370Y123010D03*
X215294D03*
X223338D03*
X219313D03*
X227061Y176337D03*
X216855Y189899D03*
X215958Y200905D03*
X213245Y241884D03*
X218800Y253544D03*
X219900Y261384D03*
X225363Y261584D03*
X223400Y268484D03*
X217120Y293778D03*
X223920Y376544D03*
X215800Y422784D03*
X233500Y96984D03*
X239590Y123010D03*
X231415D03*
X241826Y137853D03*
X231111Y176312D03*
X241200Y168384D03*
X237954Y178766D03*
X228712Y196554D03*
X239064Y212246D03*
X231021Y215721D03*
X235064D03*
X235100Y254784D03*
X239100Y253684D03*
X231250Y250434D03*
X238413Y245023D03*
X242430Y245523D03*
X242690Y260759D03*
X229265Y261907D03*
X248000Y96984D03*
X256333Y123010D03*
X243609Y123049D03*
X248087Y113123D03*
X252111D03*
X247500Y124984D03*
X252374Y137853D03*
X244500Y209484D03*
Y216484D03*
X250465Y245637D03*
X254466Y245727D03*
X246430Y245523D03*
X260346Y122510D03*
X265866Y147234D03*
X261800Y245684D03*
Y286784D03*
X265400Y420534D03*
X261400D03*
X286452Y148223D03*
X282440D03*
X282907Y186942D03*
X282240Y197743D03*
X283579Y241008D03*
X285911Y275406D03*
X281889D03*
Y285136D03*
X285911D03*
X301936Y141406D03*
X290487Y148223D03*
X301507Y192944D03*
X294162Y369036D03*
X310500Y118484D03*
X314000Y133234D03*
X310200D03*
X313936Y141406D03*
X309936D03*
X305936D03*
X305507Y192944D03*
X317116Y202434D03*
X318000Y133234D03*
X317936Y141406D03*
X321602Y190404D03*
G54D43*
X79000Y90760D03*
X70500D03*
X79000Y98240D03*
X70500D03*
X86500Y90760D03*
Y98240D03*
X95700Y90760D03*
Y98240D03*
G54D52*
X107500Y404400D03*
Y398600D03*
X137500Y123100D03*
Y128900D03*
X129928Y144932D03*
Y139132D03*
X129795Y150150D03*
Y155950D03*
X216066Y211321D03*
Y205521D03*
X266570Y131569D03*
Y137369D03*
X272311Y148785D03*
Y142985D03*
X272057Y254604D03*
Y260404D03*
X270200Y372000D03*
Y366200D03*
X277731Y148785D03*
Y142985D03*
X281000Y160100D03*
Y165900D03*
X283478Y225651D03*
Y231451D03*
X278153Y254604D03*
X283990Y254605D03*
X278153Y260404D03*
X283990Y260405D03*
X300157Y217162D03*
Y222962D03*
X294528Y221264D03*
Y227064D03*
X289102Y225598D03*
Y231398D03*
X326000Y126100D03*
Y131900D03*
X330500Y228300D03*
X322000Y235400D03*
Y229600D03*
X330500Y234100D03*
G54D61*
X150900Y12657D03*
X171400D03*
X230500Y79457D03*
X245000D03*
G54D70*
X154842Y365153D03*
Y363185D03*
X171378Y365153D03*
Y363185D03*
G54D25*
X23819Y409154D03*
X65709Y42244D03*
G54D34*
X65945Y297776D03*
X73898Y24764D03*
X100472D03*
X127047D03*
X221142D03*
X247717D03*
G54D26*
X48384Y102300D03*
X58484Y86000D03*
X50014Y220480D03*
X49984Y344000D03*
Y348000D03*
Y360000D03*
X59684Y376300D03*
X59984Y367700D03*
X49984Y368000D03*
X59684Y372600D03*
X49984Y372000D03*
X73184Y287100D03*
X78784Y296700D03*
X80984Y76000D03*
X105945Y78566D03*
X115384Y249900D03*
X117484Y358500D03*
X119484Y397000D03*
X129284Y249700D03*
X130084Y283000D03*
X125484Y277000D03*
X130484Y357500D03*
Y353500D03*
X142784Y78700D03*
X148378Y152844D03*
X151184Y182110D03*
X150568Y192600D03*
X146264Y378760D03*
Y382760D03*
X148734Y392000D03*
Y401750D03*
X158384Y119200D03*
X163684Y147000D03*
X166484Y165500D03*
X167709Y153400D03*
X166484Y169500D03*
X166684Y173200D03*
X166705Y176885D03*
X158689Y181573D03*
X158692Y185582D03*
X163468Y206305D03*
X162468Y202305D03*
X156661Y326128D03*
Y330164D03*
X174274Y300900D03*
X196384Y209700D03*
Y206200D03*
X196484Y213200D03*
X192277Y217208D03*
X184861Y238444D03*
X190174Y267000D03*
X189889Y283155D03*
X186384Y279200D03*
X189889Y287221D03*
X189857Y291172D03*
X197534Y410250D03*
X211476Y172289D03*
X203277Y177969D03*
X200337Y181969D03*
X202170Y194415D03*
X203474Y203510D03*
X206305Y216270D03*
X201898Y237255D03*
X201715Y278743D03*
X209717Y286782D03*
X201715Y282773D03*
X203734Y342250D03*
Y338750D03*
X203234Y345750D03*
Y356250D03*
Y352750D03*
Y349250D03*
Y359750D03*
Y363250D03*
Y367250D03*
Y370750D03*
X217696Y193921D03*
X225518Y216136D03*
X222484Y245800D03*
X225350Y279783D03*
X219936Y372129D03*
X238097Y171773D03*
X233935Y180866D03*
X231333Y184938D03*
X229463Y293960D03*
X236884Y374100D03*
X242364Y378220D03*
X255984Y51500D03*
X250027Y194772D03*
X253311Y276756D03*
X253284Y351200D03*
Y363100D03*
X264484Y49000D03*
X271484D03*
X264484Y53000D03*
X271596Y104703D03*
Y108226D03*
X270284Y384100D03*
X277066Y121400D03*
X298484Y97600D03*
X298884Y116300D03*
X296184Y131700D03*
X295984Y126500D03*
X301335Y205854D03*
X293198Y397365D03*
X308664Y200789D03*
X314284Y260300D03*
X314984Y369000D03*
X329372Y104676D03*
Y108692D03*
Y112707D03*
X321018Y153377D03*
X328330Y150140D03*
X328914Y155411D03*
Y167411D03*
Y163411D03*
Y175411D03*
X320893Y173378D03*
Y177378D03*
X328914Y171411D03*
X320893Y169378D03*
X324745Y203664D03*
Y207664D03*
X337309Y154911D03*
Y158911D03*
Y162911D03*
Y166911D03*
X337237Y170911D03*
X337309Y182926D03*
Y178911D03*
X337237Y174911D03*
X337309Y190961D03*
X332544Y210288D03*
Y202288D03*
Y206288D03*
X333976Y386635D03*
Y390701D03*
G54D17*
X16800Y109417D03*
X21000Y319517D03*
X48000Y94517D03*
X40400Y417317D03*
X44400D03*
X55500Y70017D03*
X59500D03*
X55500Y79017D03*
X60000Y103517D03*
X61216Y229817D03*
X64500Y69017D03*
X68500D03*
X65216Y229817D03*
X66000Y285017D03*
X74300Y274617D03*
X71900Y307017D03*
X64100Y328017D03*
X76500D03*
X78500Y400017D03*
X74500D03*
X70500D03*
X82500Y69017D03*
X90500Y72017D03*
X88700Y328017D03*
X82500Y400017D03*
X92809Y417847D03*
X88800Y417817D03*
X98500Y69517D03*
X105600Y330717D03*
X101200Y371817D03*
X103800Y381517D03*
X94500Y400017D03*
X102500D03*
X96814Y417847D03*
X115600Y118042D03*
X111600D03*
X120250Y161567D03*
X117400Y416817D03*
X132400Y88417D03*
X129500Y116517D03*
X125500Y118017D03*
X124500Y161567D03*
X127546Y228239D03*
X130000Y399517D03*
X138000Y417267D03*
X128500Y418017D03*
X139500Y141017D03*
X152450Y206311D03*
X148050Y361717D03*
X146000Y417267D03*
X150000D03*
X142000D03*
X155500Y25017D03*
X166733Y119843D03*
X156525Y150219D03*
X156467Y206311D03*
X159164Y220706D03*
X159930Y236127D03*
X160765Y257480D03*
X156695Y257492D03*
X164801Y257478D03*
X160973Y249528D03*
X156963D03*
X165013D03*
X157600Y417317D03*
X153800D03*
X179400Y14717D03*
X169500Y24517D03*
X169000Y75017D03*
X170738Y119843D03*
X178761D03*
X174741D03*
X181541Y210148D03*
X177500Y242617D03*
X173600D03*
X173992Y257348D03*
X169934Y257350D03*
X176700Y346917D03*
X181400Y362817D03*
X177500D03*
X178500Y379717D03*
X182500D03*
X185470Y93467D03*
X188980Y93477D03*
X194830Y80077D03*
X187431Y120004D03*
X191434D03*
X195500Y120017D03*
X196000Y112017D03*
X191000Y135017D03*
X195000D03*
X196332Y143933D03*
X197463Y169005D03*
X187596Y187352D03*
X193724Y186197D03*
X194567Y194614D03*
X188500Y203817D03*
X194485Y235555D03*
X198000Y261167D03*
X193800Y345417D03*
X204000Y120017D03*
X207800D03*
X199500D03*
X211370Y120037D03*
X200000Y112017D03*
X199000Y134917D03*
X207000D03*
X207486Y185986D03*
X199465Y186017D03*
X203476Y185986D03*
X206672Y209401D03*
X210333Y215572D03*
X212100Y247317D03*
X201792Y271735D03*
X208500Y258917D03*
X209811Y271735D03*
X205810D03*
X210600Y305217D03*
X227500Y93517D03*
X227370Y120043D03*
X215294D03*
X223338D03*
X219313D03*
X227061Y173370D03*
X215958Y197938D03*
X216855Y186932D03*
X213245Y238917D03*
X218800Y250577D03*
X219900Y258417D03*
X225363Y258617D03*
X223400Y265517D03*
X217120Y290811D03*
X223920Y373577D03*
X215800Y419817D03*
X233500Y94017D03*
X239590Y120043D03*
X231415D03*
X241826Y134886D03*
X241200Y165417D03*
X231111Y173345D03*
X237954Y175799D03*
X228712Y193587D03*
X231021Y212754D03*
X235064D03*
X239064Y209279D03*
X238413Y242056D03*
X242430Y242556D03*
X235100Y251817D03*
X239100Y250717D03*
X231250Y247467D03*
X242690Y257792D03*
X229265Y258940D03*
X248000Y94017D03*
X247500Y122017D03*
X256333Y120043D03*
X243609Y120082D03*
X248087Y110156D03*
X252111D03*
X252374Y134886D03*
X244500Y206517D03*
Y213517D03*
X250465Y242670D03*
X254466Y242760D03*
X246430Y242556D03*
X260346Y119543D03*
X265866Y144267D03*
X261800Y242717D03*
Y283817D03*
X265400Y417567D03*
X261400D03*
X286452Y145256D03*
X282440D03*
X282907Y183975D03*
X282240Y194776D03*
X283579Y238041D03*
X285911Y272439D03*
X281889D03*
Y282169D03*
X285911D03*
X301936Y138439D03*
X290487Y145256D03*
X301507Y189977D03*
X294162Y366069D03*
X310500Y115517D03*
X313936Y138439D03*
X309936D03*
X305936D03*
X314000Y130267D03*
X310200D03*
X305507Y189977D03*
X317116Y199467D03*
X317936Y138439D03*
X318000Y130267D03*
X321602Y187437D03*
G54D71*
X161296Y391448D03*
Y404244D03*
Y401685D03*
Y399125D03*
Y396566D03*
Y394007D03*
Y409362D03*
Y406803D03*
X181179Y316084D03*
Y313524D03*
Y310965D03*
Y308406D03*
Y305847D03*
Y323761D03*
Y321202D03*
Y318643D03*
X184296Y391448D03*
Y394007D03*
Y396566D03*
Y399125D03*
Y401685D03*
Y404244D03*
Y406803D03*
Y409362D03*
X204179Y305847D03*
Y308406D03*
Y310965D03*
Y313524D03*
Y316084D03*
Y318643D03*
Y321202D03*
Y323761D03*
X215420Y344273D03*
Y341714D03*
Y339155D03*
Y359628D03*
Y357069D03*
Y354510D03*
Y351950D03*
Y349391D03*
Y346832D03*
Y367305D03*
Y364746D03*
Y362187D03*
X238420Y339155D03*
Y341714D03*
Y344273D03*
Y346832D03*
Y349391D03*
Y351950D03*
Y354510D03*
Y357069D03*
Y359628D03*
Y362187D03*
Y364746D03*
Y367305D03*
G54D44*
X77761Y301897D03*
Y308393D03*
X86029Y301897D03*
Y308393D03*
G54D62*
X147947Y12657D03*
Y19743D03*
X168447Y12657D03*
X153853D03*
X168447Y19743D03*
X153853D03*
X174353Y12657D03*
Y19743D03*
X227547Y86543D03*
Y79457D03*
X242047Y86543D03*
Y79457D03*
X233453Y86543D03*
Y79457D03*
X247953Y86543D03*
Y79457D03*
G54D53*
X105549Y393549D03*
X110035Y392577D03*
G54D80*
X377604Y-443963D03*
X398692Y-470025D03*
X398750Y-70872D03*
X408750Y258400D03*
G54D35*
G01X20175Y105500D02*
Y103675D01*
X19200Y102700D01*
G01X25200Y116300D02*
X25100Y116200D01*
X19875D01*
G01X48500Y112559D02*
Y109000D01*
X48475Y108975D01*
Y106200D01*
G01X37875Y377925D02*
X38699D01*
X40500Y376124D01*
Y374675D01*
X40980Y374195D01*
Y374175D01*
G01X55500Y78925D02*
Y78001D01*
X55000Y77501D01*
Y76000D01*
G01X55500Y73075D02*
Y73575D01*
X55000Y74075D01*
Y76000D01*
G01X60000Y103425D02*
Y100181D01*
X58559Y98740D01*
G01X53434Y106562D02*
X54319D01*
X57456Y103425D01*
X60000D01*
G01X49500Y139000D02*
X57100Y146600D01*
Y191488D01*
X52876Y195712D01*
G01X52900Y360000D02*
Y358400D01*
X50575Y356075D01*
X50000D01*
G01X68500Y68925D02*
Y66500D01*
G01X75280Y75704D02*
X77629D01*
X77925Y76000D01*
G01X76580Y121904D02*
X83896D01*
X86700Y119100D01*
G01X66830Y122329D02*
X69770D01*
X70195Y121904D01*
X76580D01*
G01X66000Y277575D02*
X70000D01*
G01D02*
Y280000D01*
G01X69000Y390075D02*
Y392400D01*
X71000Y394400D01*
G01X75000Y390075D02*
Y390400D01*
X71000Y394400D01*
G01X86500Y68925D02*
X88000Y67425D01*
Y66500D01*
G01X88800Y417725D02*
Y415700D01*
X87600Y414500D01*
G01X98500Y69425D02*
Y66500D01*
G01X102886Y78566D02*
Y80961D01*
X104425Y82500D01*
G01X105600Y330625D02*
X105755Y330470D01*
Y327719D01*
G01X144000Y239500D02*
X142785Y240715D01*
X134819D01*
X132334Y243200D01*
X124900D01*
X124500Y242800D01*
X122876D01*
G01X122425Y277000D02*
X114400D01*
X111100Y273700D01*
G01X121175Y376800D02*
Y385125D01*
G01X126610Y377576D02*
X125834Y376800D01*
X121175D01*
G01X119791Y412301D02*
X117400Y414692D01*
Y416725D01*
G01X134075Y277000D02*
Y278573D01*
X135315Y279813D01*
G01X130575Y361500D02*
X133000D01*
G01X155205Y52677D02*
X152222D01*
X149000Y55899D01*
Y66548D01*
X152801Y70349D01*
G01X152800Y75600D02*
Y70350D01*
X152801Y70349D01*
G01X145319Y152844D02*
X143269Y150794D01*
Y150456D01*
G01X148125Y182110D02*
X146340D01*
X145296Y183154D01*
Y188835D01*
G01X147509Y192600D02*
X147097D01*
X145296Y190799D01*
Y188835D01*
G01X147509Y192600D02*
Y196145D01*
X143980Y199674D01*
G01X148050Y361625D02*
X148400Y361275D01*
Y359086D01*
X148316D01*
G01X154200Y408000D02*
X148825D01*
G01X156595Y175720D02*
X159240D01*
X161240Y177720D01*
Y177820D01*
G01X155630Y181573D02*
Y180290D01*
X156595Y179325D01*
Y175720D01*
G01X162653Y218843D02*
X164887D01*
X165824Y217906D01*
Y217706D01*
G01X158300Y232300D02*
X159800D01*
X161100Y233600D01*
X161200D01*
G01X179400Y14625D02*
X176900D01*
G01X181960Y96525D02*
Y99260D01*
G01X172575Y267000D02*
X181000D01*
G01X180600Y360200D02*
Y349547D01*
X177878Y346825D01*
X176700D01*
G01X181400Y362725D02*
Y361000D01*
X180600Y360200D01*
G01X181400Y362725D02*
X177500D01*
G01X194830Y79985D02*
X198585D01*
X201900Y83300D01*
G01X187803Y79970D02*
X194815D01*
X194830Y79985D01*
G01X187794Y200655D02*
X187700Y200749D01*
X188500Y201549D01*
G01D02*
Y203725D01*
G01X234537Y74638D02*
Y71462D01*
X234075Y71000D01*
G01X230600Y91700D02*
Y93100D01*
X231425Y93925D01*
X233500D01*
G01D02*
Y86590D01*
X233453Y86543D01*
G01X239575Y109760D02*
X240160Y109175D01*
Y107000D01*
G01X241700Y97075D02*
Y98580D01*
X240710Y99570D01*
G01X244082Y111323D02*
X242822D01*
X241259Y109760D01*
X239575D01*
G01X248000Y93925D02*
Y86590D01*
X247953Y86543D01*
G01X255000Y82700D02*
Y84442D01*
X252899Y86543D01*
X247953D01*
G01X247500Y121925D02*
X247200Y121625D01*
Y117400D01*
G01X259000Y47500D02*
X260500Y49000D01*
X261425D01*
G01X271575Y57000D02*
X273500D01*
X274500Y58000D01*
G01X263990Y368576D02*
Y369390D01*
X266575Y371975D01*
X270200D01*
G01D02*
Y372000D01*
G01Y371975D02*
X271425D01*
X273400Y370000D01*
Y363770D01*
X271990Y362360D01*
G01X307800Y259200D02*
X310125D01*
X311225Y260300D01*
G01X311575Y373000D02*
X314044D01*
X314340Y373296D01*
X62458Y346425D03*
Y343275D03*
Y355873D03*
X58564Y354280D03*
X65607Y352724D03*
Y359023D03*
Y371584D03*
X62458Y390481D03*
X75056Y346425D03*
X68757D03*
X81355D03*
X78206Y349574D03*
X68757Y352724D03*
X71906Y355873D03*
X75056Y359023D03*
X65607Y349574D03*
X71906D03*
X68757D03*
X78206Y359023D03*
X75056Y352724D03*
Y349574D03*
X78206Y355873D03*
X65607D03*
X68757Y362173D03*
Y359023D03*
X71906D03*
X75056Y355873D03*
X71906Y352724D03*
X68757Y355873D03*
X78206Y374733D03*
Y362173D03*
X75056D03*
X71906Y371584D03*
X75056Y365322D03*
X71906D03*
X68757D03*
Y371584D03*
X75056Y374733D03*
X71906D03*
X68757D03*
X65607D03*
X71906Y362173D03*
X78206Y365322D03*
Y371584D03*
X75056Y377883D03*
X68757Y384182D03*
X65607Y387332D03*
X75018Y381033D03*
X68757Y377883D03*
X78206Y381033D03*
X65607D03*
X71906Y377883D03*
X65607Y384182D03*
X68719Y381033D03*
X78206Y377883D03*
X71906Y387332D03*
X71869Y381033D03*
X71906Y384182D03*
X87617Y352724D03*
X90766Y349574D03*
X93916Y352724D03*
X81355Y355873D03*
X90766Y352724D03*
X87617Y349574D03*
X90766Y355873D03*
X87617D03*
X90766Y359023D03*
X81355Y349574D03*
X87617Y359023D03*
Y365322D03*
Y371584D03*
X81355Y365322D03*
Y371584D03*
X90766Y374733D03*
Y362173D03*
X81355D03*
X87617D03*
X81355Y374733D03*
X87617D03*
X90766Y371584D03*
Y365322D03*
X81355Y377883D03*
Y387332D03*
Y384182D03*
X87617D03*
X90766Y377883D03*
X87617Y390481D03*
X81355Y381033D03*
X87617Y387332D03*
X90766Y381033D03*
X87617Y377883D03*
X90766Y390481D03*
Y387332D03*
Y384182D03*
X92360Y394175D03*
X89210D03*
X103365Y346425D03*
X106564Y346400D03*
X100253Y346387D03*
X100215Y352724D03*
X103383Y349556D03*
X93916Y359023D03*
X97066Y355873D03*
X93916Y349574D03*
X97066D03*
X106515Y352724D03*
X106514Y349574D03*
X97066Y352724D03*
X100215Y355873D03*
X93916D03*
X100215Y349574D03*
X103383Y387350D03*
X100215Y384182D03*
X93916Y377883D03*
X97066Y381033D03*
X100215Y387332D03*
X97066D03*
X93916Y384182D03*
X97066D03*
X100215Y381033D03*
X93916D03*
Y387332D03*
X166300Y212300D03*
X175359Y153286D03*
X181495Y153449D03*
X175196Y159748D03*
X178346Y162898D03*
Y156599D03*
X181495Y159748D03*
X175196Y156599D03*
X181495D03*
Y166047D03*
X184645D03*
X181495Y162898D03*
X178346Y159748D03*
Y172347D03*
X181495Y178646D03*
Y175496D03*
X184645Y181795D03*
X181495D03*
Y172347D03*
X184645Y175496D03*
X174569Y180202D03*
X178346Y175496D03*
X175196Y172347D03*
X173000Y170200D03*
X181495Y169197D03*
X178346Y184945D03*
X181495D03*
Y197506D03*
X178346D03*
Y191244D03*
X181495D03*
X175196Y197506D03*
X174336Y192800D03*
X181495Y188095D03*
X178346D03*
X175196Y200655D03*
X178346D03*
Y210104D03*
X181495Y203805D03*
Y206955D03*
X175196Y210104D03*
X178346Y206955D03*
X175196D03*
Y203805D03*
X178346D03*
X171836Y200655D03*
Y198300D03*
X181495Y200655D03*
X178346Y213254D03*
Y225852D03*
X181495Y219553D03*
X175196Y213254D03*
X184645Y219553D03*
X178346Y229002D03*
X181495Y225852D03*
Y222703D03*
X184645Y229002D03*
X174600Y217800D03*
X181495Y216403D03*
X174079Y234604D03*
X175196Y229002D03*
X181495D03*
X187794Y153449D03*
X192400Y152804D03*
X184645Y153449D03*
X197243Y156599D03*
X187794Y159748D03*
X197243Y166047D03*
X194094Y162898D03*
X197243Y159748D03*
X194094D03*
X197243Y162898D03*
X184645Y156599D03*
X187794Y162898D03*
Y166047D03*
X184645Y162898D03*
Y159748D03*
X190944Y162898D03*
Y159748D03*
X194094Y166047D03*
X190944D03*
X200393Y162898D03*
X187794Y156599D03*
Y178646D03*
X197243D03*
X187794Y181795D03*
X194094Y169197D03*
X190944Y172347D03*
Y175496D03*
X197243D03*
X190944Y178646D03*
Y181795D03*
X187794Y175496D03*
X184645Y178646D03*
X190944Y169197D03*
X187794Y172347D03*
X184645Y169197D03*
Y172347D03*
X187794Y169197D03*
X197243Y191244D03*
Y197506D03*
Y184945D03*
X190944Y197506D03*
Y184945D03*
Y188095D03*
Y191244D03*
X187794Y197506D03*
Y184945D03*
X184645Y197506D03*
Y184945D03*
Y191244D03*
Y188095D03*
X197243Y203805D03*
X184645Y206955D03*
X197243Y200655D03*
X190944D03*
Y210104D03*
Y203805D03*
X187794Y200655D03*
X184645Y210104D03*
Y200655D03*
Y203805D03*
X187794Y210104D03*
X190944Y219553D03*
X194094Y222703D03*
X200393Y229002D03*
X194094Y225852D03*
X187794D03*
Y219553D03*
X197243D03*
X187794Y213254D03*
X190944D03*
Y222702D03*
X200393Y222703D03*
X197243Y225852D03*
Y222703D03*
X184645Y225852D03*
X187794Y222703D03*
X184645D03*
Y213254D03*
X194094Y219553D03*
Y232151D03*
X184645D03*
X187794Y229002D03*
X197243Y235301D03*
X194094Y229002D03*
X197243D03*
Y232151D03*
X209842Y153449D03*
Y159748D03*
X206692Y156599D03*
X209842D03*
X203542Y166047D03*
X206692Y162898D03*
X203542D03*
X200393Y159748D03*
X209842Y166047D03*
Y162898D03*
X212991D03*
X203542Y159748D03*
X200393Y166047D03*
X206692D03*
X212991D03*
X206692Y159748D03*
X209842Y169197D03*
X203542D03*
X212991D03*
X206692D03*
X212991Y181795D03*
X206692Y178646D03*
X209842Y181795D03*
X200393Y169197D03*
X206692Y181795D03*
X203542Y175496D03*
X206692D03*
X209842D03*
X200393D03*
X203542Y191244D03*
X206692D03*
X209842Y184945D03*
X200393Y191244D03*
X203542Y197506D03*
X209842D03*
X212991Y184945D03*
Y197506D03*
X203542Y210104D03*
X212991Y206955D03*
Y210104D03*
X209842D03*
X200393D03*
X203542Y200655D03*
X209842D03*
X203542Y206955D03*
X212991Y203805D03*
X206692Y206955D03*
X209842D03*
X200393D03*
X212991Y200655D03*
Y219553D03*
Y213254D03*
X200393D03*
Y219553D03*
X212991Y222740D03*
X209842Y213254D03*
Y225852D03*
X203542Y222703D03*
X200393Y225852D03*
X206692Y219553D03*
X203542Y225852D03*
X206692Y229002D03*
X212991D03*
X203542Y219553D03*
X206692Y222703D03*
X209842D03*
X212991Y225890D03*
X206692Y225852D03*
X203542Y229002D03*
Y232151D03*
X209746Y235397D03*
X203542Y235301D03*
X209842Y232151D03*
X200393D03*
X206692D03*
X212991D03*
X209842Y229002D03*
X225658Y153369D03*
X225552Y156599D03*
Y159748D03*
X222402Y162898D03*
X219253Y166047D03*
X225552Y162898D03*
Y166047D03*
X222402D03*
X219253Y159748D03*
X222402D03*
X219253Y162898D03*
Y156599D03*
X222402D03*
X217697Y174852D03*
X219253Y178646D03*
X225552D03*
X222402Y169197D03*
Y178646D03*
X225552Y181795D03*
X214547Y174852D03*
X225552Y169197D03*
X219253D03*
X219290Y191207D03*
X225552Y184945D03*
Y197543D03*
Y191244D03*
Y188095D03*
X222402Y191244D03*
X219253Y197506D03*
X222402D03*
X219253Y188095D03*
X222402Y206955D03*
X219253Y200655D03*
Y206955D03*
Y210104D03*
Y203805D03*
X222402Y213254D03*
X219253D03*
X228739Y222703D03*
X216141D03*
X228702Y229002D03*
X225590Y222720D03*
X216103Y219591D03*
X219253Y219553D03*
X225590Y225852D03*
X222440Y222703D03*
X225552Y219553D03*
X222402D03*
Y229002D03*
X222440Y225852D03*
X219290D03*
Y222703D03*
X219253Y232151D03*
X225552Y229002D03*
X219253D03*
X235001Y153449D03*
X228702Y162898D03*
X238150D03*
X235001Y166047D03*
X231851D03*
X238150D03*
X228702Y159748D03*
Y166047D03*
X238150Y156599D03*
X235001D03*
X231851D03*
Y162898D03*
Y159748D03*
X235001Y162898D03*
Y159748D03*
X238150D03*
X241300D03*
X228702Y169197D03*
X238150D03*
X231851D03*
Y178646D03*
X235001Y169197D03*
X241300Y175496D03*
Y178646D03*
Y172347D03*
X235001Y178646D03*
Y175496D03*
X228702Y181795D03*
Y178646D03*
X231851Y191244D03*
X241300D03*
X235001Y184945D03*
X228702Y191244D03*
X235001Y188095D03*
Y191244D03*
Y197506D03*
X241300Y184945D03*
Y197506D03*
Y188095D03*
X235001Y200655D03*
Y206955D03*
X244450Y200655D03*
X228702D03*
X235001Y203805D03*
X231851D03*
X228702D03*
X241300Y200655D03*
Y210104D03*
X235001D03*
X231851D03*
X228702D03*
X235001Y219553D03*
X241300Y213254D03*
X238150Y219553D03*
X238188Y225852D03*
X228702Y219553D03*
X228739Y213254D03*
X235038Y225890D03*
X228739Y225852D03*
X238150Y222703D03*
X231889Y219591D03*
Y222740D03*
X235038D03*
X231889Y225890D03*
X228739Y216441D03*
X241338Y225890D03*
X238630Y235654D03*
X231851Y232151D03*
X241300D03*
X231851Y229002D03*
X241300D03*
X239870Y237596D03*
X242870D03*
X235038Y229039D03*
X255492Y152905D03*
X244450Y156599D03*
X250749Y159748D03*
X244450D03*
X250749Y169197D03*
X247637Y162898D03*
X247599Y166047D03*
X253898Y172347D03*
Y178646D03*
X247599Y181795D03*
Y175496D03*
X253898Y169197D03*
X257048Y172347D03*
X250749Y181795D03*
X244450D03*
X250749Y175496D03*
Y178646D03*
X247599Y172347D03*
X244450Y175496D03*
X250749Y172347D03*
X247599Y178646D03*
X253898Y175496D03*
X244450Y178646D03*
Y172347D03*
X250749Y184945D03*
X244450Y169197D03*
X253898Y191244D03*
Y184945D03*
X247599Y197506D03*
Y188095D03*
X244450Y197506D03*
X247599Y191244D03*
X257048Y197506D03*
X253898D03*
X250749D03*
X247599Y184945D03*
X244450Y188095D03*
X257048Y191244D03*
X250749Y188095D03*
X244450Y184945D03*
X250749Y191244D03*
X244450D03*
X247599Y203805D03*
X253898Y206955D03*
Y200655D03*
X250749Y203805D03*
X247599Y206955D03*
Y210104D03*
X250749Y206955D03*
X247599Y200655D03*
X257048Y206955D03*
X250749Y200655D03*
X257048D03*
X250749Y210104D03*
X244450Y203805D03*
X250749Y222703D03*
Y225852D03*
X253898Y219553D03*
Y222703D03*
X257048Y225890D03*
Y219553D03*
X250749D03*
X257048Y213254D03*
X250749D03*
X247599D03*
X253898D03*
X247637Y225852D03*
X250749Y232151D03*
X257048Y235301D03*
X244020Y235518D03*
X244487Y229002D03*
X244450Y232151D03*
X247599D03*
X253898D03*
X257048D03*
X250749Y229002D03*
X253898D03*
X250749Y235301D03*
X253898D03*
X268510Y179088D03*
X262880Y178977D03*
X267722Y176791D03*
X264222D03*
X270472Y188488D03*
X264118Y188095D03*
X268391Y207262D03*
X260269Y207358D03*
X266080Y207262D03*
X262580D03*
X269391Y214593D03*
X261269Y214657D03*
X263580Y214593D03*
X267080D03*
X285980Y163487D03*
X285482Y168102D03*
X286105Y172936D03*
Y182385D03*
X273644Y174267D03*
X282975Y172975D03*
X286105Y176085D03*
X285482Y190187D03*
X286105Y197989D03*
Y185534D03*
Y194839D03*
Y201139D03*
Y204288D03*
Y213721D03*
X289110Y163487D03*
X292260D03*
X295410Y169786D03*
X292404Y176085D03*
X289254Y172792D03*
X292260Y169643D03*
X295410Y179235D03*
X292384Y172936D03*
X289254Y176085D03*
Y182385D03*
X292260Y179235D03*
X289111D03*
X297372Y196616D03*
X292361Y197970D03*
X292404Y191690D03*
X289254D03*
X292404Y185534D03*
Y194983D03*
X295410Y194839D03*
X295411Y185534D03*
X289254D03*
Y197989D03*
X289091Y204331D03*
X289254Y210587D03*
X292404D03*
X289254Y201139D03*
X295410Y210587D03*
X289254Y213737D03*
X308008Y163487D03*
X311158D03*
X308008Y166637D03*
X314307Y163487D03*
X314930Y168140D03*
X311301Y182385D03*
X314930Y171289D03*
Y177588D03*
X305002Y176085D03*
Y169786D03*
X308152D03*
X311158Y169643D03*
X308152Y172936D03*
Y176085D03*
Y182385D03*
X305002Y179235D03*
X308152D03*
X314930Y180738D03*
Y174439D03*
X311158Y185534D03*
X314307Y191690D03*
X308008D03*
X311158D03*
X308008Y188540D03*
Y185391D03*
Y198133D03*
X314307Y185534D03*
X311158Y188540D03*
X308008Y194839D03*
X311158Y197989D03*
X314307Y194839D03*
Y197989D03*
X311158Y204288D03*
X314307Y207438D03*
X303940Y212664D03*
X311158Y201139D03*
X308008Y207438D03*
X308152Y204432D03*
X305002D03*
X308008Y210731D03*
X305002Y210587D03*
X314307Y201139D03*
Y204288D03*
Y210587D03*
X308460Y214178D03*
X311158Y213737D03*
X314307D03*
G54D90*
G01X27660Y109200D02*
X26099D01*
X22399Y105500D01*
X20175D01*
G01X66874Y130590D02*
X65490D01*
X63890Y128990D01*
Y123929D01*
X65490Y122329D01*
X66830D01*
G54D36*
X62550Y349850D03*
G54D45*
X70313Y354280D03*
X73463D03*
X70313Y357429D03*
X73463D03*
X70312Y351130D03*
X73462D03*
X76589Y370000D03*
X70312Y373177D03*
X73462D03*
X70312Y376327D03*
X73462D03*
X79739Y370000D03*
X98659Y351130D03*
X101809D03*
Y354280D03*
X104959D03*
X103425Y357500D03*
X106575D03*
X93711Y374528D03*
X96861D03*
X94425Y367500D03*
X97575D03*
X94425Y371000D03*
X97575D03*
G54D27*
X45417Y102300D03*
X47047Y220480D03*
X47017Y344000D03*
Y348000D03*
Y360000D03*
Y368000D03*
Y372000D03*
X55517Y86000D03*
X56717Y376300D03*
X57017Y367700D03*
X56717Y372600D03*
X78017Y76000D03*
X70217Y287100D03*
X75817Y296700D03*
X102978Y78566D03*
X112417Y249900D03*
X122517Y277000D03*
X114517Y358500D03*
X116517Y397000D03*
X126317Y249700D03*
X127117Y283000D03*
X127517Y357500D03*
Y353500D03*
X139817Y78700D03*
X145411Y152844D03*
X148217Y182110D03*
X147601Y192600D03*
X143297Y378760D03*
Y382760D03*
X145767Y392000D03*
Y401750D03*
X155417Y119200D03*
X160717Y147000D03*
X163517Y165500D03*
X164742Y153400D03*
X163517Y169500D03*
X163717Y173200D03*
X163738Y176885D03*
X155722Y181573D03*
X155725Y185582D03*
X160501Y206305D03*
X159501Y202305D03*
X153694Y326128D03*
Y330164D03*
X181894Y238444D03*
X171307Y300900D03*
X197370Y181969D03*
X193417Y209700D03*
Y206200D03*
X193517Y213200D03*
X189310Y217208D03*
X187207Y267000D03*
X186922Y283155D03*
X183417Y279200D03*
X186922Y287221D03*
X186890Y291172D03*
X194567Y410250D03*
X208509Y172289D03*
X200310Y177969D03*
X199203Y194415D03*
X200507Y203510D03*
X203338Y216270D03*
X198931Y237255D03*
X198748Y278743D03*
X206750Y286782D03*
X198748Y282773D03*
X200767Y342250D03*
Y338750D03*
X200267Y345750D03*
Y356250D03*
Y352750D03*
Y349250D03*
Y359750D03*
Y363250D03*
Y367250D03*
Y370750D03*
X214729Y193921D03*
X222551Y216136D03*
X219517Y245800D03*
X222383Y279783D03*
X226496Y293960D03*
X216969Y372129D03*
X235130Y171773D03*
X230968Y180866D03*
X228366Y184938D03*
X233917Y374100D03*
X239397Y378220D03*
X253017Y51500D03*
X247060Y194772D03*
X250344Y276756D03*
X250317Y351200D03*
Y363100D03*
X261517Y49000D03*
X268517D03*
X261517Y53000D03*
X268629Y104703D03*
Y108226D03*
X267317Y384100D03*
X274099Y121400D03*
X295517Y97600D03*
X295917Y116300D03*
X293217Y131700D03*
X293017Y126500D03*
X298368Y205854D03*
X290231Y397365D03*
X305697Y200789D03*
X311317Y260300D03*
X312017Y369000D03*
X326405Y104676D03*
Y108692D03*
Y112707D03*
X318051Y153377D03*
X325363Y150140D03*
X325947Y155411D03*
Y167411D03*
Y163411D03*
Y175411D03*
X317926Y173378D03*
Y177378D03*
X325947Y171411D03*
X317926Y169378D03*
X321778Y203664D03*
X329577Y210288D03*
X321778Y207664D03*
X329577Y202288D03*
Y206288D03*
X331009Y386635D03*
Y390701D03*
X334342Y154911D03*
Y158911D03*
Y162911D03*
Y166911D03*
X334270Y170911D03*
X334342Y182926D03*
Y178911D03*
X334270Y174911D03*
X334342Y190961D03*
G54D81*
X377664Y-210141D03*
X398780Y-115203D03*
X398750Y214188D03*
X408750Y412460D03*
G54D54*
X116500Y78889D03*
Y83711D03*
G54D72*
X178355Y87450D03*
Y83710D03*
Y79970D03*
X187803D03*
Y87450D03*
G54D18*
X18800Y122100D03*
X19000Y129500D03*
X18500Y163300D03*
X7809Y168397D03*
X21400Y178100D03*
X7809Y183397D03*
Y198397D03*
X19100Y187420D03*
X7809Y213397D03*
Y228397D03*
X18000Y234500D03*
X7809Y243397D03*
Y258397D03*
X17065Y255712D03*
X7809Y273397D03*
Y288397D03*
X8200Y302800D03*
X22000Y111400D03*
X36500Y129500D03*
X29000D03*
X24000Y138500D03*
X26000Y209500D03*
X27500Y202000D03*
X28000Y223500D03*
X26000Y216500D03*
X29900Y231400D03*
X32100Y252800D03*
X24705Y258767D03*
X22237Y304626D03*
X30638Y304602D03*
Y311957D03*
X33000Y318700D03*
X35300Y323900D03*
X29100Y327000D03*
X36200Y368400D03*
X31500Y428500D03*
X40175Y29713D03*
X40000Y104200D03*
X45000Y122500D03*
X37500Y116500D03*
X40940Y112559D03*
X51500Y114000D03*
X45000Y129500D03*
X49400Y161800D03*
X47294Y184491D03*
X48035Y191535D03*
X39408Y195990D03*
X48940Y204871D03*
X40600Y203000D03*
X39900Y211000D03*
X39567Y243133D03*
X47800Y240843D03*
X51500Y258200D03*
X37485Y258807D03*
X41100Y248900D03*
X47440Y304225D03*
X39039Y301299D03*
Y311933D03*
X50950Y318050D03*
X44481Y328760D03*
X38560Y329739D03*
X37020Y385600D03*
X46100Y412700D03*
X38000Y428800D03*
X45100Y435800D03*
X45300Y426400D03*
X59549Y63000D03*
X59945Y117795D03*
X60800Y137000D03*
X52410Y186900D03*
X59700Y196200D03*
X65380Y213120D03*
X52948Y200700D03*
X58000Y217700D03*
X55100Y225500D03*
X64500Y240400D03*
X59500Y240500D03*
X61200Y276400D03*
Y282600D03*
X55500Y315000D03*
X65400Y311900D03*
X60600Y318000D03*
X52800Y322400D03*
X59820Y341030D03*
X66070Y339780D03*
X65400Y344200D03*
X54500Y341390D03*
X54530Y348200D03*
X54500Y355000D03*
X59600Y363100D03*
X65000Y377500D03*
X54800Y381800D03*
X54600Y388000D03*
X61924Y383476D03*
X55500Y395600D03*
X58000Y412600D03*
X63715Y412385D03*
X62455Y426870D03*
X78781Y64635D03*
X74757Y83745D03*
X76580Y121904D03*
X66900Y125300D03*
X76500Y135000D03*
X70450Y138610D03*
X71124Y178565D03*
X66700Y220520D03*
X71100Y229741D03*
X74583Y217314D03*
X76200Y247400D03*
X77437Y262760D03*
X72300Y282500D03*
X77500Y316100D03*
X73301Y319575D03*
X81000Y321900D03*
X78900Y336600D03*
X71700Y340600D03*
X74500Y335700D03*
X81355Y390300D03*
X79000Y395500D03*
X73976Y408665D03*
X69139Y413452D03*
X74782Y413800D03*
X73971Y429200D03*
X91358Y83745D03*
X88500Y128000D03*
X81500Y176515D03*
X87500Y237300D03*
X92300Y282100D03*
X94812Y301312D03*
X93000Y315000D03*
X88700Y318300D03*
X92698Y323224D03*
X84800Y344100D03*
X92900Y342800D03*
X88700Y337123D03*
X83900Y385700D03*
X94200Y391000D03*
X96030Y409400D03*
X84320Y430510D03*
X94710Y433260D03*
X89500Y432000D03*
X84000Y425500D03*
X105722Y59722D03*
X111000Y77000D03*
X104500Y73500D03*
X110950Y82050D03*
X111075Y104600D03*
X98720Y236980D03*
X103580Y237400D03*
X106600Y253689D03*
X106574Y280028D03*
X99990Y307900D03*
X100500Y328547D03*
X98377Y341523D03*
X105900Y376900D03*
X98500Y394800D03*
X108701Y418300D03*
X108336Y411547D03*
X109048Y425853D03*
X106550Y431630D03*
X103461Y425875D03*
X125800Y47330D03*
X112800Y60400D03*
X112600Y52800D03*
X125800Y69000D03*
X113000Y88500D03*
X123325Y111000D03*
X120500Y115525D03*
X120300Y134800D03*
X118990Y128536D03*
X113590Y245170D03*
X112900Y239200D03*
X124559Y255500D03*
X115475Y254900D03*
X111600Y262730D03*
X113157Y270929D03*
X111600Y284000D03*
X122957Y300991D03*
X123100Y295974D03*
X124935Y324900D03*
X124300Y348800D03*
X114060Y340640D03*
X119370Y344050D03*
X122200Y356400D03*
X111950Y371200D03*
X122047Y372260D03*
X125650Y368650D03*
X122330Y364670D03*
X119200Y389700D03*
X117410Y381350D03*
X112800Y421600D03*
X116632Y411500D03*
X122498Y419675D03*
X112796Y412490D03*
X117900Y425980D03*
X140730Y72600D03*
X133000Y78900D03*
X126800Y132900D03*
X140500Y134500D03*
X132500Y167300D03*
X128900Y183700D03*
X135300Y175100D03*
X133433Y186400D03*
X138900Y219500D03*
X127200Y223700D03*
X134891Y225171D03*
X138608Y235001D03*
X133608D03*
X138000Y244600D03*
X137059Y255568D03*
X134788Y283000D03*
X136100Y334000D03*
X140950Y390050D03*
X127950Y395750D03*
X134400Y394600D03*
X129135Y410250D03*
X128866Y433066D03*
X135350Y433016D03*
X128500Y426070D03*
X140820Y433030D03*
X134805Y427395D03*
X143000Y17310D03*
X146200Y28075D03*
X151000Y24925D03*
X152801Y70349D03*
X152800Y75600D03*
X145100Y87400D03*
X147587Y119813D03*
X149800Y135100D03*
X144800Y141700D03*
X148429Y147682D03*
X144500Y169570D03*
X146882Y177501D03*
X148967Y173433D03*
X141694Y196204D03*
X145100Y208800D03*
X143742Y203395D03*
X152400Y226300D03*
X142702Y227817D03*
X149862Y243788D03*
X150430Y231000D03*
X145250Y256890D03*
X152300Y248200D03*
X147150Y273000D03*
X141890Y310570D03*
X153500Y373400D03*
X145703Y370700D03*
X150210Y369250D03*
X148490Y374259D03*
X153330Y391710D03*
X152500Y382600D03*
X150820Y387325D03*
X154110Y404090D03*
X154638Y396566D03*
X146000Y429900D03*
X141185Y426899D03*
X158732Y12625D03*
X158952Y20203D03*
X169500Y32000D03*
X165000Y24500D03*
X156710Y73420D03*
X168985Y71000D03*
X156286Y124903D03*
X166733Y128700D03*
X159328Y160847D03*
X164000Y197700D03*
X169000Y199000D03*
X157500Y214700D03*
X170600Y204300D03*
X170000Y223500D03*
X169520Y252810D03*
X160300Y281848D03*
X161635Y276500D03*
X160850Y301344D03*
X170800Y317600D03*
X159510Y312500D03*
X161154Y376704D03*
X156300Y376300D03*
X165501Y382800D03*
X158200Y381400D03*
X162100Y414000D03*
X156101Y425100D03*
X165500Y433100D03*
X184500Y15500D03*
X182108Y129094D03*
X174553Y128728D03*
X175400Y149000D03*
X175450Y143704D03*
X181752Y147052D03*
X171507Y162892D03*
X171600Y178000D03*
X171677Y172607D03*
X171443Y183557D03*
X176800Y194200D03*
X176144Y232863D03*
X179754Y250150D03*
X180458Y258825D03*
X174400Y251936D03*
X181863Y289871D03*
X175013Y281583D03*
X178900Y301100D03*
X172800Y354646D03*
X178682Y430173D03*
X184480Y429370D03*
X174830Y427848D03*
X172060Y433100D03*
X190500Y18000D03*
X193100Y69100D03*
X194600Y89900D03*
X194500Y106200D03*
X186891Y113991D03*
X187435Y129623D03*
X195983Y129294D03*
X187172Y143672D03*
X200400Y151600D03*
X193267Y278328D03*
X200396Y291531D03*
X194294Y300400D03*
X187180Y329590D03*
X187570Y337590D03*
X194200Y351930D03*
X189500Y368900D03*
X187400Y379400D03*
X187300Y384300D03*
X197660Y390870D03*
X195800Y396780D03*
X190370Y422490D03*
X199940Y423700D03*
X197600Y415400D03*
X194600Y419660D03*
X192470Y414850D03*
X188239Y417654D03*
X195300Y432327D03*
X204100Y67400D03*
X204504Y113507D03*
X211490Y143700D03*
X202247Y145400D03*
X211300Y151100D03*
X207610Y242910D03*
X210770Y313524D03*
X210930Y318643D03*
X202440Y333420D03*
X208320Y348291D03*
X208300Y338200D03*
X208315Y343235D03*
X208340Y353360D03*
X208350Y358370D03*
X208120Y363410D03*
X202240Y378980D03*
X208350Y369750D03*
X210550Y375290D03*
X208360Y384890D03*
X208565Y404501D03*
X205223Y422665D03*
X206150Y412821D03*
X223800Y50700D03*
X224000Y74275D03*
X226000Y68000D03*
X216400Y106400D03*
X226040Y101220D03*
X222100Y112100D03*
X229342Y129240D03*
X221278Y129294D03*
X228766Y142545D03*
X218631Y151131D03*
X221400Y142600D03*
X223007Y153967D03*
X217000Y233800D03*
X227820Y233900D03*
X230196Y267477D03*
X218400Y270400D03*
X226783Y298849D03*
X216384Y312216D03*
X228800Y312100D03*
X218500Y318800D03*
X219220Y307580D03*
X216250Y328130D03*
X228680Y376635D03*
X222575Y387625D03*
X227206Y400100D03*
X220134Y400780D03*
X240000Y67400D03*
X235630Y104990D03*
X231592Y110500D03*
X235880Y115000D03*
X242500Y129000D03*
X236623Y128797D03*
X239118Y145170D03*
X239624Y154064D03*
X232384Y148884D03*
X244850Y153350D03*
X238385Y232466D03*
X235070Y236989D03*
X239298Y268800D03*
X241277Y274649D03*
X234946Y271298D03*
X235108Y262780D03*
X241263Y282654D03*
X239693Y288930D03*
X234693D03*
X238900Y296950D03*
X245300Y361100D03*
X234815Y379895D03*
X243250Y385930D03*
X256000Y56000D03*
X259106Y66000D03*
X252900Y80400D03*
X254900Y92500D03*
X256500Y98500D03*
X257422Y129840D03*
X258500Y146400D03*
X247546Y142562D03*
X252586Y142376D03*
X248988Y157001D03*
X258500Y169000D03*
X259200Y163600D03*
X260000Y210900D03*
X259800Y222600D03*
X247700Y229400D03*
X259000Y237600D03*
X259500Y258800D03*
X250900Y250800D03*
X253100Y257800D03*
X258100Y295080D03*
X245900Y305000D03*
X246000Y333900D03*
X257046Y331377D03*
X254340Y346320D03*
X256320Y341490D03*
X256124Y336355D03*
X245400Y355800D03*
X245430Y367305D03*
X257095Y428796D03*
X267939Y41122D03*
X272505Y83545D03*
X267060Y124750D03*
X268256Y112794D03*
X272100Y137400D03*
X260733Y154500D03*
X267909Y185096D03*
X271209Y177524D03*
X264200Y172300D03*
X266346Y219380D03*
X264100Y235500D03*
X266647Y252636D03*
X261800Y250300D03*
X260500Y300500D03*
X262310Y311225D03*
X261300Y334100D03*
X274190Y408900D03*
X269700Y411379D03*
X271500Y418300D03*
X267100Y432900D03*
X263800Y430300D03*
X272999Y430500D03*
X262190Y425300D03*
X286000Y47000D03*
X290000Y82000D03*
X277505Y83545D03*
X282505D03*
X278394Y111035D03*
X278220Y101530D03*
X288116Y120306D03*
X280400Y126000D03*
X287796Y131542D03*
X288280Y126212D03*
X286000Y157000D03*
X287908Y170320D03*
X289254Y194839D03*
X286106Y210587D03*
X289000Y244900D03*
X288192Y237704D03*
X289701Y255679D03*
X278029Y249108D03*
X284357Y267027D03*
X287507Y301596D03*
X289939Y309060D03*
X289600Y322253D03*
X286372Y326768D03*
X283973Y382553D03*
X285472Y394583D03*
X278900Y421400D03*
X281300Y416200D03*
X277700Y412580D03*
X280765Y431556D03*
X297466Y51521D03*
X297575Y73738D03*
X290840Y96350D03*
X304000Y116500D03*
X291360Y116390D03*
X300500Y125000D03*
X296075Y122000D03*
X292200Y154900D03*
X300819Y154564D03*
X292572Y160025D03*
X295410Y172936D03*
X298714Y210477D03*
X292404Y201282D03*
X299667Y201334D03*
X292404Y213737D03*
X290700Y221600D03*
X303688Y237034D03*
X303918Y243252D03*
X299100Y286500D03*
X291000Y297700D03*
X298705Y369127D03*
X298152Y393332D03*
X292700Y403700D03*
X317000Y111500D03*
X315100Y116400D03*
X309394Y153989D03*
X311269Y159165D03*
X310598Y174488D03*
X305002Y172936D03*
X310866Y179672D03*
X311158Y194839D03*
Y210587D03*
X309521Y226397D03*
X305700Y216300D03*
X309521Y235352D03*
X319700Y248600D03*
X316276Y255376D03*
X312114Y288439D03*
X312272Y282107D03*
X307668Y285160D03*
X306200Y308800D03*
X307000Y367500D03*
X310431Y393352D03*
X308926Y401900D03*
X321800Y109000D03*
X320938Y122677D03*
X322530Y138950D03*
X331641Y141743D03*
X328798Y216364D03*
X323798D03*
X322700Y288600D03*
X330200D03*
X322700Y296100D03*
Y303600D03*
X330200D03*
Y296100D03*
X325900Y365643D03*
X326100Y375717D03*
X326200Y370681D03*
X326375Y380724D03*
X333300Y403400D03*
X321100Y410400D03*
X339101Y117328D03*
X337842Y128533D03*
X335400Y133400D03*
X343600Y133900D03*
X337700Y144300D03*
Y227900D03*
X347500Y350000D03*
X335475Y367500D03*
X347500Y388000D03*
X335500Y380000D03*
G54D63*
X153237Y58583D03*
X165048Y52677D03*
X161111Y58583D03*
X168985D03*
X182764Y52677D03*
X172922D03*
X176859Y58583D03*
X184733D03*
G54D91*
G01X304657Y181885D02*
X305846Y183074D01*
X307394D01*
X308152Y182385D01*
G01X304657Y185885D02*
X305968Y184574D01*
X307266D01*
X308008Y185391D01*
G01X451000Y-355000D02*
X447550D01*
X446750Y-355800D01*
Y-363185D01*
X444672Y-365263D01*
X426100D01*
X424900Y-366463D01*
Y-368863D01*
X426100Y-370063D01*
X470522D01*
X472600Y-372141D01*
Y-375785D01*
X470522Y-377863D01*
X426000D01*
X424800Y-379063D01*
Y-381463D01*
X426000Y-382663D01*
X470622D01*
X472700Y-384741D01*
Y-388385D01*
X470622Y-390463D01*
X424000D01*
X422800Y-391663D01*
Y-394063D01*
X424000Y-395263D01*
X468622D01*
X470700Y-397341D01*
Y-400985D01*
X468622Y-403063D01*
X424000D01*
X422800Y-404263D01*
Y-406663D01*
X424000Y-407863D01*
X468622D01*
X470700Y-409941D01*
Y-413585D01*
X468622Y-415663D01*
X424000D01*
X422800Y-416863D01*
Y-419263D01*
X424000Y-420463D01*
X468622D01*
X470700Y-422541D01*
Y-426185D01*
X468622Y-428263D01*
X424000D01*
X422800Y-429463D01*
Y-431863D01*
X424000Y-433063D01*
X444672D01*
X446750Y-435141D01*
Y-443200D01*
X447550Y-444000D01*
X451000D01*
G01X441000Y-355000D02*
X444450D01*
X445250Y-355800D01*
Y-362563D01*
X444050Y-363763D01*
X425478D01*
X423400Y-365841D01*
Y-369485D01*
X425478Y-371563D01*
X469900D01*
X471100Y-372763D01*
Y-375163D01*
X469900Y-376363D01*
X425378D01*
X423300Y-378441D01*
Y-382085D01*
X425378Y-384163D01*
X470000D01*
X471200Y-385363D01*
Y-387763D01*
X470000Y-388963D01*
X423378D01*
X421300Y-391041D01*
Y-394685D01*
X423378Y-396763D01*
X468000D01*
X469200Y-397963D01*
Y-400363D01*
X468000Y-401563D01*
X423378D01*
X421300Y-403641D01*
Y-407285D01*
X423378Y-409363D01*
X468000D01*
X469200Y-410563D01*
Y-412963D01*
X468000Y-414163D01*
X423378D01*
X421300Y-416241D01*
Y-419885D01*
X423378Y-421963D01*
X468000D01*
X469200Y-423163D01*
Y-425563D01*
X468000Y-426763D01*
X423378D01*
X421300Y-428841D01*
Y-432485D01*
X423378Y-434563D01*
X444050D01*
X445250Y-435763D01*
Y-443200D01*
X444450Y-444000D01*
X441000D01*
G54D46*
X76664Y376425D03*
X76612Y363729D03*
Y366879D03*
X76664Y379575D03*
X70332Y379457D03*
Y382607D03*
X83864Y362325D03*
Y365475D03*
X79852Y363825D03*
Y366975D03*
X104958Y347981D03*
Y351131D03*
X98664Y382625D03*
Y385775D03*
G54D37*
X60451Y347751D03*
G54D73*
X177037Y418500D03*
X169163Y414760D03*
Y422240D03*
X237937Y390000D03*
X230063Y386260D03*
Y393740D03*
X253294Y394747D03*
X261168Y391007D03*
Y398487D03*
G54D55*
X125100Y75091D03*
Y86509D03*
G54D82*
X376620Y-440713D03*
X378588D03*
X378648Y-213391D03*
X376680D03*
X397708Y-466775D03*
X399676D03*
X399764Y-118453D03*
X397796D03*
X397766Y-67622D03*
X399734D03*
Y210938D03*
X397766D03*
X407766Y261650D03*
X409734D03*
Y409210D03*
X407766D03*
G54D28*
X44500Y212516D03*
X40980Y371116D03*
X48500Y417516D03*
X59500Y79016D03*
X56100Y328016D03*
X60000D03*
X52200D03*
X50000Y353016D03*
X56500Y417516D03*
X52500D03*
X60500D03*
X72500Y69016D03*
X76500D03*
X69500Y236016D03*
X66000Y274516D03*
X70000D03*
X68000Y316516D03*
X72000Y328016D03*
X68100D03*
X75000Y387016D03*
X69000D03*
X86500Y69016D03*
X80600Y254916D03*
X86500Y400016D03*
X94500Y69516D03*
X104000Y361016D03*
X98500Y400016D03*
X112500Y126016D03*
X123500Y125016D03*
X119370Y348796D03*
X135500Y141016D03*
X126000Y399516D03*
X152000Y252816D03*
Y260016D03*
X163400Y12716D03*
X162657Y119842D03*
X166717Y134885D03*
X173000Y75016D03*
X181960Y93466D03*
X170737Y134885D03*
X182954D03*
X174740D03*
X178816D03*
X177300Y216816D03*
X181300Y242516D03*
X169700Y243316D03*
X172800Y346916D03*
X178000Y338841D03*
X178500Y379716D03*
X182500D03*
X182600Y414966D03*
X187000Y135016D03*
X193343Y178502D03*
X193550Y171692D03*
X184890Y242531D03*
X192501Y250273D03*
X188500Y250266D03*
X190693Y243069D03*
X194729D03*
X197790Y271734D03*
X187070Y259426D03*
X194100Y261196D03*
X187220Y346016D03*
X210800Y134885D03*
X202900Y135016D03*
X206912Y144205D03*
X211494Y187150D03*
X198990Y242028D03*
X202990D03*
X206238Y235265D03*
X200460Y250276D03*
X204000Y261116D03*
X221500Y64516D03*
X214500Y135016D03*
X218500D03*
X222500D03*
X226500D03*
X215498Y169217D03*
X216265Y179907D03*
X222190Y185945D03*
X217200Y238716D03*
X223269Y237916D03*
X227116Y249940D03*
X214100Y255716D03*
X223100Y249316D03*
X213833Y267608D03*
X217862Y275753D03*
X213813Y275762D03*
X222293Y283801D03*
X221154Y290810D03*
X241700Y94016D03*
X235510Y120042D03*
X234500Y135216D03*
X230500Y135016D03*
X238025Y186882D03*
X238337Y198169D03*
X232713Y198176D03*
X230520Y238916D03*
X253000Y72016D03*
X244082Y108264D03*
X256100Y110116D03*
X245836Y134885D03*
X252600Y126316D03*
X256700Y134885D03*
X257500Y274016D03*
X250300Y367816D03*
X243250Y392766D03*
X260200Y134886D03*
X261863Y144338D03*
X268897Y159446D03*
X263897D03*
X271470Y216445D03*
X281000Y76016D03*
X277000D03*
X285000D03*
X276000Y162516D03*
X278868Y183974D03*
X282192Y201791D03*
X286611Y216625D03*
X283383Y245668D03*
X301936Y146388D03*
X297357Y233233D03*
X305000Y121016D03*
X313936Y146388D03*
X309936D03*
X305936D03*
X316979Y192460D03*
X317111Y208525D03*
X317936Y146388D03*
G54D64*
X144685Y297776D03*
G54D19*
X30859Y14328D03*
X31500Y443500D03*
X137400Y323800D03*
X205900Y99500D03*
X270100Y198000D03*
X297000Y270500D03*
G54D92*
G01X73462Y351130D02*
X75070D01*
G01X73462D02*
Y352704D01*
G54D38*
X60036Y389478D03*
G54D56*
X122156Y141343D03*
Y154257D03*
X113000Y141500D03*
Y154414D03*
G54D74*
X227510Y57613D03*
X234990D03*
X231250Y65487D03*
X294157Y376023D03*
X297897Y383897D03*
X290417D03*
X308486Y378422D03*
X312226Y386296D03*
X304746D03*
G54D47*
X73482Y382626D03*
Y379476D03*
X89210Y360579D03*
Y357429D03*
X83900Y359275D03*
Y356125D03*
X82911Y376327D03*
Y373177D03*
X86061Y376327D03*
Y373177D03*
X89210Y376327D03*
Y373177D03*
G54D29*
X44500Y215483D03*
X40980Y374083D03*
X48500Y420483D03*
X59500Y81983D03*
X56100Y330983D03*
X60000D03*
X52200D03*
X50000Y355983D03*
X56500Y420483D03*
X52500D03*
X60500D03*
X72500Y71983D03*
X76500D03*
X69500Y238983D03*
X66000Y277483D03*
X70000D03*
X68000Y319483D03*
X72000Y330983D03*
X68100D03*
X75000Y389983D03*
X69000D03*
X86500Y71983D03*
X80600Y257883D03*
X86500Y402983D03*
X94500Y72483D03*
X104000Y363983D03*
X98500Y402983D03*
X112500Y128983D03*
X123500Y127983D03*
X119370Y351763D03*
X135500Y143983D03*
X126000Y402483D03*
X152000Y255783D03*
Y262983D03*
X163400Y15683D03*
X162657Y122809D03*
X166717Y137852D03*
X173000Y77983D03*
X181960Y96433D03*
X170737Y137852D03*
X182954D03*
X174740D03*
X178816D03*
X177300Y219783D03*
X169700Y246283D03*
X181300Y245483D03*
X178000Y341808D03*
X172800Y349883D03*
X178500Y382683D03*
X182500D03*
X182600Y417933D03*
X187000Y137983D03*
X193343Y181469D03*
X193550Y174659D03*
X192501Y253240D03*
X188500Y253233D03*
X190693Y246036D03*
X194729D03*
X184890Y245498D03*
X187070Y262393D03*
X194100Y264163D03*
X197790Y274701D03*
X187220Y348983D03*
X210800Y137852D03*
X202900Y137983D03*
X206912Y147172D03*
X211494Y190117D03*
X206238Y238232D03*
X200460Y253243D03*
X198990Y244995D03*
X202990D03*
X204000Y264083D03*
X221500Y67483D03*
X214500Y137983D03*
X218500D03*
X222500D03*
X226500D03*
X215498Y172184D03*
X216265Y182874D03*
X222190Y188912D03*
X217200Y241683D03*
X223269Y240883D03*
X227116Y252907D03*
X223100Y252283D03*
X213833Y270575D03*
X214100Y258683D03*
X217862Y278720D03*
X213813Y278729D03*
X222293Y286768D03*
X221154Y293777D03*
X241700Y96983D03*
X235510Y123009D03*
X234500Y138183D03*
X230500Y137983D03*
X238025Y189849D03*
X238337Y201136D03*
X232713Y201143D03*
X230520Y241883D03*
X253000Y74983D03*
X256100Y113083D03*
X244082Y111231D03*
X245836Y137852D03*
X252600Y129283D03*
X256700Y137852D03*
X257500Y276983D03*
X250300Y370783D03*
X243250Y395733D03*
X260200Y137853D03*
X261863Y147305D03*
X268897Y162413D03*
X263897D03*
X271470Y219412D03*
X281000Y78983D03*
X277000D03*
X285000D03*
X276000Y165483D03*
X278868Y186941D03*
X282192Y204758D03*
X286611Y219592D03*
X283383Y248635D03*
X301936Y149355D03*
X297357Y236200D03*
X305000Y123983D03*
X313936Y149355D03*
X309936D03*
X305936D03*
X316979Y195427D03*
X317111Y211492D03*
X317936Y149355D03*
G54D83*
X441000Y-444000D03*
X451000D03*
Y-355000D03*
X441000D03*
Y-323400D03*
X451000D03*
Y-245000D03*
X441000D03*
X451000Y-215000D03*
X441000D03*
Y-136600D03*
X451000D03*
Y-107000D03*
X441000D03*
Y-18000D03*
X451000D03*
X441000Y12000D03*
X451000D03*
Y96000D03*
X441000D03*
Y126000D03*
X451000D03*
Y200000D03*
X441000D03*
X451000Y230000D03*
X441000D03*
Y304000D03*
X451000D03*
Y336000D03*
X441000D03*
Y420000D03*
X451000D03*
G54D65*
X151420Y432880D03*
X204056Y128935D03*
X261800Y107300D03*
X261700Y114700D03*
G54D93*
G01X2010999Y-388000D02*
Y1475775D01*
X-407000D01*
Y-386798D01*
Y-755294D01*
Y-793716D01*
X-368578D01*
X1942346D01*
X2010999D01*
Y-725063D01*
Y-388000D01*
G01X-53307Y-609436D02*
Y-684436D01*
X446693D01*
Y-609436D01*
X-53307D01*
G01X-41307Y-674436D02*
Y-679436D01*
G01X-42764Y-674436D02*
X-39850D01*
G01X-34940Y-679436D02*
X-37474D01*
Y-674436D01*
X-34940D01*
G01X-35954Y-676853D02*
X-37474D01*
G01X-32374Y-674436D02*
Y-679436D01*
X-29840D01*
G01X-26007Y-679603D02*
X-26134Y-679519D01*
Y-679353D01*
X-26007Y-679269D01*
X-25880Y-679353D01*
Y-679519D01*
X-26007Y-679603D01*
G01Y-677353D02*
X-26134Y-677269D01*
Y-677103D01*
X-26007Y-677019D01*
X-25880Y-677103D01*
Y-677269D01*
X-26007Y-677353D01*
G01X-21224Y-681103D02*
X-21857Y-680269D01*
X-22174Y-679436D01*
Y-676103D01*
X-21857Y-675269D01*
X-21224Y-674436D01*
G01X-15807D02*
X-16314Y-674603D01*
X-16694Y-675019D01*
X-16947Y-675519D01*
X-17137Y-676186D01*
X-17200Y-676936D01*
X-17137Y-677686D01*
X-16947Y-678353D01*
X-16694Y-678853D01*
X-16314Y-679269D01*
X-15807Y-679436D01*
X-15300Y-679269D01*
X-14920Y-678853D01*
X-14667Y-678353D01*
X-14477Y-677686D01*
X-14414Y-676936D01*
X-14477Y-676186D01*
X-14667Y-675519D01*
X-14920Y-675019D01*
X-15300Y-674603D01*
X-15807Y-674436D01*
G01X-12100Y-678436D02*
X-11720Y-679019D01*
X-11214Y-679353D01*
X-10644Y-679436D01*
X-10137Y-679353D01*
X-9630Y-678936D01*
X-9314Y-678436D01*
X-9250Y-677936D01*
X-9377Y-677353D01*
X-9820Y-676936D01*
X-10264Y-676769D01*
X-10834D01*
G01X-10264D02*
X-9884Y-676519D01*
X-9567Y-676103D01*
X-9440Y-675603D01*
X-9567Y-675103D01*
X-9884Y-674686D01*
X-10454Y-674436D01*
X-11024Y-674519D01*
X-11594Y-674853D01*
G01X-5290Y-681103D02*
X-4657Y-680269D01*
X-4340Y-679436D01*
Y-676103D01*
X-4657Y-675269D01*
X-5290Y-674436D01*
G01X-1900Y-678436D02*
X-1520Y-679019D01*
X-1014Y-679353D01*
X-444Y-679436D01*
X63Y-679353D01*
X570Y-678936D01*
X886Y-678436D01*
X950Y-677936D01*
X823Y-677353D01*
X380Y-676936D01*
X-64Y-676769D01*
X-634D01*
G01X-64D02*
X316Y-676519D01*
X633Y-676103D01*
X760Y-675603D01*
X633Y-675103D01*
X316Y-674686D01*
X-254Y-674436D01*
X-824Y-674519D01*
X-1394Y-674853D01*
G01X3390Y-675269D02*
X3770Y-674769D01*
X4213Y-674519D01*
X4720Y-674436D01*
X5353Y-674603D01*
X5796Y-675019D01*
X5923Y-675519D01*
X5860Y-676019D01*
X5606Y-676436D01*
X4340Y-677269D01*
X3770Y-677853D01*
X3390Y-678686D01*
X3263Y-679436D01*
X5923D01*
G01X9566D02*
X9693Y-678353D01*
X9883Y-677436D01*
X10136Y-676603D01*
X10453Y-675686D01*
X10960Y-674436D01*
X8426D01*
G01X13970Y-677769D02*
X15616D01*
G01X18690Y-675269D02*
X19070Y-674769D01*
X19513Y-674519D01*
X20020Y-674436D01*
X20653Y-674603D01*
X21096Y-675019D01*
X21223Y-675519D01*
X21160Y-676019D01*
X20906Y-676436D01*
X19640Y-677269D01*
X19070Y-677853D01*
X18690Y-678686D01*
X18563Y-679436D01*
X21223D01*
G01X23600Y-678436D02*
X23980Y-679019D01*
X24486Y-679353D01*
X25056Y-679436D01*
X25563Y-679353D01*
X26070Y-678936D01*
X26386Y-678436D01*
X26450Y-677936D01*
X26323Y-677353D01*
X25880Y-676936D01*
X25436Y-676769D01*
X24866D01*
G01X25436D02*
X25816Y-676519D01*
X26133Y-676103D01*
X26260Y-675603D01*
X26133Y-675103D01*
X25816Y-674686D01*
X25246Y-674436D01*
X24676Y-674519D01*
X24106Y-674853D01*
G01X30853Y-679436D02*
Y-674436D01*
X28510Y-678019D01*
X31676D01*
G01X33800Y-678686D02*
X34180Y-679103D01*
X34623Y-679353D01*
X35193Y-679436D01*
X35763Y-679269D01*
X36206Y-678936D01*
X36523Y-678353D01*
X36586Y-677686D01*
X36460Y-677019D01*
X36143Y-676603D01*
X35700Y-676269D01*
X35256Y-676186D01*
X34813Y-676269D01*
X34243Y-676603D01*
X34433Y-674436D01*
X36143D01*
G01X44190Y-679436D02*
Y-674436D01*
X46596D01*
G01X45710Y-676853D02*
X44190D01*
G01X48910Y-679436D02*
X50493Y-674436D01*
X52076Y-679436D01*
G01X51506Y-677686D02*
X49480D01*
G01X54263Y-679436D02*
X56923Y-674436D01*
G01X54263D02*
X56923Y-679436D01*
G01X60693Y-679603D02*
X60566Y-679519D01*
Y-679353D01*
X60693Y-679269D01*
X60820Y-679353D01*
Y-679519D01*
X60693Y-679603D01*
G01Y-677353D02*
X60566Y-677269D01*
Y-677103D01*
X60693Y-677019D01*
X60820Y-677103D01*
Y-677269D01*
X60693Y-677353D01*
G01X65476Y-681103D02*
X64843Y-680269D01*
X64526Y-679436D01*
Y-676103D01*
X64843Y-675269D01*
X65476Y-674436D01*
G01X70893D02*
X70386Y-674603D01*
X70006Y-675019D01*
X69753Y-675519D01*
X69563Y-676186D01*
X69500Y-676936D01*
X69563Y-677686D01*
X69753Y-678353D01*
X70006Y-678853D01*
X70386Y-679269D01*
X70893Y-679436D01*
X71400Y-679269D01*
X71780Y-678853D01*
X72033Y-678353D01*
X72223Y-677686D01*
X72286Y-676936D01*
X72223Y-676186D01*
X72033Y-675519D01*
X71780Y-675019D01*
X71400Y-674603D01*
X70893Y-674436D01*
G01X74600Y-678436D02*
X74980Y-679019D01*
X75486Y-679353D01*
X76056Y-679436D01*
X76563Y-679353D01*
X77070Y-678936D01*
X77386Y-678436D01*
X77450Y-677936D01*
X77323Y-677353D01*
X76880Y-676936D01*
X76436Y-676769D01*
X75866D01*
G01X76436D02*
X76816Y-676519D01*
X77133Y-676103D01*
X77260Y-675603D01*
X77133Y-675103D01*
X76816Y-674686D01*
X76246Y-674436D01*
X75676Y-674519D01*
X75106Y-674853D01*
G01X81410Y-681103D02*
X82043Y-680269D01*
X82360Y-679436D01*
Y-676103D01*
X82043Y-675269D01*
X81410Y-674436D01*
G01X84800Y-678436D02*
X85180Y-679019D01*
X85686Y-679353D01*
X86256Y-679436D01*
X86763Y-679353D01*
X87270Y-678936D01*
X87586Y-678436D01*
X87650Y-677936D01*
X87523Y-677353D01*
X87080Y-676936D01*
X86636Y-676769D01*
X86066D01*
G01X86636D02*
X87016Y-676519D01*
X87333Y-676103D01*
X87460Y-675603D01*
X87333Y-675103D01*
X87016Y-674686D01*
X86446Y-674436D01*
X85876Y-674519D01*
X85306Y-674853D01*
G01X90216Y-678853D02*
X90660Y-679269D01*
X91166Y-679436D01*
X91673Y-679269D01*
X92116Y-678769D01*
X92433Y-678019D01*
X92560Y-677269D01*
Y-676353D01*
X92433Y-675603D01*
X92116Y-674936D01*
X91736Y-674603D01*
X91293Y-674436D01*
X90786Y-674603D01*
X90406Y-674936D01*
X90153Y-675436D01*
X90026Y-676103D01*
X90153Y-676686D01*
X90470Y-677269D01*
X90850Y-677603D01*
X91293Y-677686D01*
X91800Y-677519D01*
X92180Y-677103D01*
X92560Y-676353D01*
G01X96266Y-679436D02*
X96393Y-678353D01*
X96583Y-677436D01*
X96836Y-676603D01*
X97153Y-675686D01*
X97660Y-674436D01*
X95126D01*
G01X100670Y-677769D02*
X102316D01*
G01X105200Y-678436D02*
X105580Y-679019D01*
X106086Y-679353D01*
X106656Y-679436D01*
X107163Y-679353D01*
X107670Y-678936D01*
X107986Y-678436D01*
X108050Y-677936D01*
X107923Y-677353D01*
X107480Y-676936D01*
X107036Y-676769D01*
X106466D01*
G01X107036D02*
X107416Y-676519D01*
X107733Y-676103D01*
X107860Y-675603D01*
X107733Y-675103D01*
X107416Y-674686D01*
X106846Y-674436D01*
X106276Y-674519D01*
X105706Y-674853D01*
G01X110490Y-677353D02*
X110933Y-676769D01*
X111313Y-676436D01*
X111820Y-676269D01*
X112263Y-676436D01*
X112580Y-676769D01*
X112833Y-677269D01*
X112896Y-677853D01*
X112833Y-678353D01*
X112580Y-678853D01*
X112200Y-679269D01*
X111756Y-679436D01*
X111250Y-679269D01*
X110806Y-678769D01*
X110553Y-678019D01*
X110490Y-677186D01*
X110616Y-676103D01*
X110806Y-675519D01*
X111123Y-674936D01*
X111566Y-674519D01*
X112010Y-674436D01*
X112453Y-674603D01*
X112770Y-675019D01*
G01X116793Y-679436D02*
Y-674436D01*
X116033Y-675436D01*
G01Y-679436D02*
X117553D01*
G01X122653D02*
Y-674436D01*
X120310Y-678019D01*
X123476D01*
G01X141693Y-609436D02*
Y-684436D01*
G01Y-659436D02*
X244693D01*
Y-634436D01*
G01X141693D02*
X244693D01*
G01X246693Y-609436D02*
Y-684436D01*
G01X244693Y-609436D02*
Y-684436D01*
G01X252200Y-669436D02*
Y-664436D01*
X253466D01*
X253973Y-664686D01*
X254353Y-665019D01*
X254670Y-665519D01*
X254923Y-666103D01*
X254986Y-666936D01*
X254923Y-667769D01*
X254670Y-668353D01*
X254353Y-668853D01*
X253973Y-669186D01*
X253466Y-669436D01*
X252200D01*
G01X257110D02*
X258693Y-664436D01*
X260276Y-669436D01*
G01X259706Y-667686D02*
X257680D01*
G01X263793Y-664436D02*
Y-669436D01*
G01X262336Y-664436D02*
X265250D01*
G01X270160Y-669436D02*
X267626D01*
Y-664436D01*
X270160D01*
G01X269146Y-666853D02*
X267626D01*
G01X273993Y-669603D02*
X273866Y-669519D01*
Y-669353D01*
X273993Y-669269D01*
X274120Y-669353D01*
Y-669519D01*
X273993Y-669603D01*
G01Y-667353D02*
X273866Y-667269D01*
Y-667103D01*
X273993Y-667019D01*
X274120Y-667103D01*
Y-667269D01*
X273993Y-667353D01*
G01X246693Y-659436D02*
X446693D01*
G01X252326Y-644436D02*
Y-639436D01*
X253846D01*
X254353Y-639686D01*
X254733Y-640269D01*
X254860Y-640936D01*
X254733Y-641603D01*
X254416Y-642103D01*
X253846Y-642353D01*
X252326D01*
G01X257553Y-644603D02*
X259833Y-639436D01*
G01X262336Y-644436D02*
Y-639436D01*
X265250Y-644436D01*
Y-639436D01*
G01X268893Y-644603D02*
X268766Y-644519D01*
Y-644353D01*
X268893Y-644269D01*
X269020Y-644353D01*
Y-644519D01*
X268893Y-644603D01*
G01Y-642353D02*
X268766Y-642269D01*
Y-642103D01*
X268893Y-642019D01*
X269020Y-642103D01*
Y-642269D01*
X268893Y-642353D01*
G01X246693Y-634436D02*
X446693D01*
G01X252326Y-619436D02*
Y-614436D01*
X253846D01*
X254353Y-614686D01*
X254733Y-615269D01*
X254860Y-615936D01*
X254733Y-616603D01*
X254416Y-617103D01*
X253846Y-617353D01*
X252326D01*
G01X257426Y-619436D02*
Y-614436D01*
X259010D01*
X259516Y-614686D01*
X259833Y-615019D01*
X259960Y-615686D01*
X259833Y-616353D01*
X259453Y-616769D01*
X259010Y-617019D01*
X257426D01*
G01X259010D02*
X259960Y-619436D01*
G01X263793D02*
X263286Y-619353D01*
X262843Y-619019D01*
X262463Y-618519D01*
X262210Y-617936D01*
X262083Y-617269D01*
Y-616603D01*
X262210Y-615936D01*
X262463Y-615353D01*
X262843Y-614853D01*
X263286Y-614519D01*
X263793Y-614436D01*
X264300Y-614519D01*
X264743Y-614853D01*
X265123Y-615353D01*
X265376Y-615936D01*
X265503Y-616603D01*
Y-617269D01*
X265376Y-617936D01*
X265123Y-618519D01*
X264743Y-619019D01*
X264300Y-619353D01*
X263793Y-619436D01*
G01X267626Y-618436D02*
X267943Y-618936D01*
X268323Y-619269D01*
X268766Y-619436D01*
X269273Y-619269D01*
X269653Y-618936D01*
X270033Y-618436D01*
X270160Y-617769D01*
Y-614436D01*
G01X275260Y-619436D02*
X272726D01*
Y-614436D01*
X275260D01*
G01X274246Y-616853D02*
X272726D01*
G01X280486Y-614853D02*
X280106Y-614603D01*
X279663Y-614436D01*
X279156D01*
X278586Y-614686D01*
X278143Y-615103D01*
X277826Y-615603D01*
X277573Y-616436D01*
X277510Y-617186D01*
X277636Y-617936D01*
X277826Y-618436D01*
X278206Y-618936D01*
X278650Y-619269D01*
X279093Y-619436D01*
X279536D01*
X279980Y-619269D01*
X280360Y-619019D01*
X280676Y-618686D01*
G01X284193Y-614436D02*
Y-619436D01*
G01X282736Y-614436D02*
X285650D01*
G01X289293Y-619603D02*
X289166Y-619519D01*
Y-619353D01*
X289293Y-619269D01*
X289420Y-619353D01*
Y-619519D01*
X289293Y-619603D01*
G01Y-617353D02*
X289166Y-617269D01*
Y-617103D01*
X289293Y-617019D01*
X289420Y-617103D01*
Y-617269D01*
X289293Y-617353D01*
G01X361693Y-659436D02*
Y-684436D01*
G01X364326Y-661936D02*
Y-666936D01*
X366860D01*
G01X369933Y-661936D02*
X371453D01*
G01X370693D02*
Y-666936D01*
G01X369933D02*
X371453D01*
G01X376300Y-664269D02*
X376553Y-664019D01*
X376743Y-663603D01*
X376870Y-663019D01*
X376743Y-662519D01*
X376490Y-662186D01*
X376046Y-661936D01*
X374336D01*
Y-666936D01*
X376426D01*
X376870Y-666603D01*
X377123Y-666103D01*
X377250Y-665519D01*
X377123Y-664936D01*
X376743Y-664436D01*
X376300Y-664269D01*
X374336D01*
G01X380893Y-667103D02*
X380766Y-667019D01*
Y-666853D01*
X380893Y-666769D01*
X381020Y-666853D01*
Y-667019D01*
X380893Y-667103D01*
G01Y-664853D02*
X380766Y-664769D01*
Y-664603D01*
X380893Y-664519D01*
X381020Y-664603D01*
Y-664769D01*
X380893Y-664853D01*
G01X404693Y-659436D02*
Y-684436D01*
G01Y-634436D02*
Y-659436D01*
G01X412706Y-687603D02*
X412813Y-687478D01*
X412893Y-687269D01*
X412946Y-686978D01*
X412893Y-686728D01*
X412786Y-686561D01*
X412600Y-686436D01*
X411880D01*
Y-688936D01*
X412760D01*
X412946Y-688769D01*
X413053Y-688519D01*
X413106Y-688228D01*
X413053Y-687936D01*
X412893Y-687686D01*
X412706Y-687603D01*
X411880D01*
G01X415173Y-688936D02*
Y-687269D01*
G01Y-687561D02*
X415066Y-687394D01*
X414906Y-687311D01*
X414720Y-687269D01*
X414533Y-687353D01*
X414373Y-687519D01*
X414266Y-687769D01*
X414213Y-688103D01*
X414266Y-688436D01*
X414373Y-688686D01*
X414533Y-688853D01*
X414720Y-688936D01*
X414906Y-688894D01*
X415066Y-688769D01*
X415173Y-688603D01*
G01X416493Y-688644D02*
X416626Y-688811D01*
X416813Y-688936D01*
X416973D01*
X417133Y-688853D01*
X417240Y-688728D01*
X417293Y-688561D01*
X417266Y-688311D01*
X417160Y-688186D01*
X416680Y-687936D01*
X416573Y-687644D01*
X416626Y-687436D01*
X416733Y-687311D01*
X416893Y-687269D01*
X417053Y-687311D01*
X417213Y-687436D01*
G01X418693Y-687811D02*
X419546D01*
X419466Y-687519D01*
X419333Y-687353D01*
X419146Y-687269D01*
X418960Y-687311D01*
X418800Y-687436D01*
X418693Y-687728D01*
X418640Y-687978D01*
Y-688228D01*
X418693Y-688478D01*
X418826Y-688728D01*
X418986Y-688894D01*
X419173Y-688936D01*
X419360Y-688853D01*
X419546Y-688603D01*
G01X420813Y-688936D02*
Y-686436D01*
G01Y-687686D02*
X420946Y-687436D01*
X421106Y-687311D01*
X421266Y-687269D01*
X421506Y-687353D01*
X421666Y-687519D01*
X421773Y-687811D01*
Y-688144D01*
X421720Y-688478D01*
X421613Y-688728D01*
X421426Y-688894D01*
X421266Y-688936D01*
X421106Y-688894D01*
X420946Y-688769D01*
X420813Y-688561D01*
G01X423493Y-688936D02*
X423333Y-688894D01*
X423173Y-688728D01*
X423066Y-688436D01*
X423013Y-688103D01*
X423066Y-687769D01*
X423173Y-687478D01*
X423333Y-687311D01*
X423493Y-687269D01*
X423653Y-687311D01*
X423813Y-687478D01*
X423920Y-687769D01*
X423946Y-688103D01*
X423920Y-688436D01*
X423813Y-688728D01*
X423653Y-688894D01*
X423493Y-688936D01*
G01X426173D02*
Y-687269D01*
G01Y-687561D02*
X426066Y-687394D01*
X425906Y-687311D01*
X425720Y-687269D01*
X425533Y-687353D01*
X425373Y-687519D01*
X425266Y-687769D01*
X425213Y-688103D01*
X425266Y-688436D01*
X425373Y-688686D01*
X425533Y-688853D01*
X425720Y-688936D01*
X425906Y-688894D01*
X426066Y-688769D01*
X426173Y-688603D01*
G01X427520Y-688936D02*
Y-687269D01*
G01Y-687603D02*
X427653Y-687436D01*
X427786Y-687311D01*
X427973Y-687269D01*
X428106Y-687311D01*
X428266Y-687436D01*
G01X430573Y-686436D02*
Y-688936D01*
G01Y-688561D02*
X430466Y-688769D01*
X430306Y-688894D01*
X430120Y-688936D01*
X429906Y-688853D01*
X429746Y-688644D01*
X429640Y-688394D01*
X429613Y-688103D01*
X429640Y-687811D01*
X429746Y-687561D01*
X429906Y-687353D01*
X430120Y-687269D01*
X430306Y-687311D01*
X430440Y-687394D01*
X430573Y-687561D01*
G01X433960Y-688936D02*
Y-686436D01*
X434626D01*
X434840Y-686561D01*
X434973Y-686728D01*
X435026Y-687061D01*
X434973Y-687394D01*
X434813Y-687603D01*
X434626Y-687728D01*
X433960D01*
G01X434626D02*
X435026Y-688936D01*
G01X436293Y-687811D02*
X437146D01*
X437066Y-687519D01*
X436933Y-687353D01*
X436746Y-687269D01*
X436560Y-687311D01*
X436400Y-687436D01*
X436293Y-687728D01*
X436240Y-687978D01*
Y-688228D01*
X436293Y-688478D01*
X436426Y-688728D01*
X436586Y-688894D01*
X436773Y-688936D01*
X436960Y-688853D01*
X437146Y-688603D01*
G01X438413Y-687269D02*
X438893Y-688936D01*
X439373Y-687269D01*
G01X441093Y-689019D02*
X441040Y-688978D01*
Y-688894D01*
X441093Y-688853D01*
X441146Y-688894D01*
Y-688978D01*
X441093Y-689019D01*
G01X443613Y-688936D02*
Y-686436D01*
X442626Y-688228D01*
X443960D01*
G01X444826Y-688936D02*
X445493Y-686436D01*
X446160Y-688936D01*
G01X445920Y-688061D02*
X445066D01*
G01X408593Y-661936D02*
Y-666936D01*
G01X407136Y-661936D02*
X410050D01*
G01X413693Y-666936D02*
X413313Y-666853D01*
X412933Y-666519D01*
X412680Y-665936D01*
X412553Y-665269D01*
X412680Y-664603D01*
X412933Y-664019D01*
X413313Y-663686D01*
X413693Y-663603D01*
X414073Y-663686D01*
X414453Y-664019D01*
X414706Y-664603D01*
X414770Y-665269D01*
X414706Y-665936D01*
X414453Y-666519D01*
X414073Y-666853D01*
X413693Y-666936D01*
G01X418793D02*
X418413Y-666853D01*
X418033Y-666519D01*
X417780Y-665936D01*
X417653Y-665269D01*
X417780Y-664603D01*
X418033Y-664019D01*
X418413Y-663686D01*
X418793Y-663603D01*
X419173Y-663686D01*
X419553Y-664019D01*
X419806Y-664603D01*
X419870Y-665269D01*
X419806Y-665936D01*
X419553Y-666519D01*
X419173Y-666853D01*
X418793Y-666936D01*
G01X423893D02*
Y-661936D01*
G01X428993Y-667103D02*
X428866Y-667019D01*
Y-666853D01*
X428993Y-666769D01*
X429120Y-666853D01*
Y-667019D01*
X428993Y-667103D01*
G01Y-664853D02*
X428866Y-664769D01*
Y-664603D01*
X428993Y-664519D01*
X429120Y-664603D01*
Y-664769D01*
X428993Y-664853D01*
G01X407326Y-641936D02*
Y-636936D01*
X408910D01*
X409416Y-637186D01*
X409733Y-637519D01*
X409860Y-638186D01*
X409733Y-638853D01*
X409353Y-639269D01*
X408910Y-639519D01*
X407326D01*
G01X408910D02*
X409860Y-641936D01*
G01X414960D02*
X412426D01*
Y-636936D01*
X414960D01*
G01X413946Y-639353D02*
X412426D01*
G01X417210Y-636936D02*
X418793Y-641936D01*
X420376Y-636936D01*
G01X423893Y-642103D02*
X423766Y-642019D01*
Y-641853D01*
X423893Y-641769D01*
X424020Y-641853D01*
Y-642019D01*
X423893Y-642103D01*
G01Y-639853D02*
X423766Y-639769D01*
Y-639603D01*
X423893Y-639519D01*
X424020Y-639603D01*
Y-639769D01*
X423893Y-639853D01*
G01X2010999Y-388000D02*
Y1475775D01*
X-407000D01*
Y-386798D01*
Y-755294D01*
Y-793716D01*
X-368578D01*
X1942346D01*
X2010999D01*
Y-725063D01*
Y-388000D01*
G01X-42602Y-671096D02*
X-41975Y-671621D01*
X-41270Y-671936D01*
X-40644D01*
X-40017Y-671621D01*
X-39547Y-671096D01*
X-39312Y-670361D01*
X-39469Y-669626D01*
X-39860Y-668996D01*
X-40565Y-668576D01*
X-41505Y-668366D01*
X-42054Y-667946D01*
X-42289Y-667211D01*
X-42132Y-666476D01*
X-41740Y-665951D01*
X-41192Y-665636D01*
X-40644D01*
X-40095Y-665846D01*
X-39625Y-666371D01*
G01X-36302Y-671936D02*
Y-665636D01*
G01X-33012D02*
Y-671936D01*
G01Y-668786D02*
X-36302D01*
G01X-29297Y-665636D02*
X-27417D01*
G01X-28357D02*
Y-671936D01*
G01X-29297D02*
X-27417D01*
G01X-20490D02*
X-23624D01*
Y-665636D01*
X-20490D01*
G01X-21744Y-668681D02*
X-23624D01*
G01X-17559Y-671936D02*
Y-665636D01*
X-13955Y-671936D01*
Y-665636D01*
G01X-9614Y-673091D02*
X-9300Y-671726D01*
G01X-3157Y-665636D02*
Y-671936D01*
G01X-4959Y-665636D02*
X-1355D01*
G01X1185Y-671936D02*
X3143Y-665636D01*
X5101Y-671936D01*
G01X4396Y-669731D02*
X1890D01*
G01X8503Y-665636D02*
X10383D01*
G01X9443D02*
Y-671936D01*
G01X8503D02*
X10383D01*
G01X13393Y-665636D02*
X14490Y-671936D01*
X15743Y-665636D01*
X16996Y-671936D01*
X18093Y-665636D01*
G01X20085Y-671936D02*
X22043Y-665636D01*
X24001Y-671936D01*
G01X23296Y-669731D02*
X20790D01*
G01X26541Y-671936D02*
Y-665636D01*
X30145Y-671936D01*
Y-665636D01*
G01X39376Y-671936D02*
Y-665636D01*
X41335D01*
X41961Y-665951D01*
X42353Y-666371D01*
X42510Y-667211D01*
X42353Y-668051D01*
X41883Y-668576D01*
X41335Y-668891D01*
X39376D01*
G01X41335D02*
X42510Y-671936D01*
G01X47243Y-672146D02*
X47086Y-672041D01*
Y-671831D01*
X47243Y-671726D01*
X47400Y-671831D01*
Y-672041D01*
X47243Y-672146D01*
G01X53543Y-671936D02*
X52916Y-671831D01*
X52368Y-671411D01*
X51898Y-670781D01*
X51585Y-670046D01*
X51428Y-669206D01*
Y-668366D01*
X51585Y-667526D01*
X51898Y-666791D01*
X52368Y-666161D01*
X52916Y-665741D01*
X53543Y-665636D01*
X54170Y-665741D01*
X54718Y-666161D01*
X55188Y-666791D01*
X55501Y-667526D01*
X55658Y-668366D01*
Y-669206D01*
X55501Y-670046D01*
X55188Y-670781D01*
X54718Y-671411D01*
X54170Y-671831D01*
X53543Y-671936D01*
G01X59843Y-672146D02*
X59686Y-672041D01*
Y-671831D01*
X59843Y-671726D01*
X60000Y-671831D01*
Y-672041D01*
X59843Y-672146D01*
G01X67866Y-666161D02*
X67396Y-665846D01*
X66848Y-665636D01*
X66221D01*
X65516Y-665951D01*
X64968Y-666476D01*
X64576Y-667106D01*
X64263Y-668156D01*
X64185Y-669101D01*
X64341Y-670046D01*
X64576Y-670676D01*
X65046Y-671306D01*
X65595Y-671726D01*
X66143Y-671936D01*
X66691D01*
X67240Y-671726D01*
X67710Y-671411D01*
X68101Y-670991D01*
G01X72443Y-672146D02*
X72286Y-672041D01*
Y-671831D01*
X72443Y-671726D01*
X72600Y-671831D01*
Y-672041D01*
X72443Y-672146D01*
G01X-42680Y-661936D02*
Y-655636D01*
G01X-39704D02*
X-42680Y-659521D01*
G01X-39234Y-661936D02*
X-41349Y-657736D01*
G01X-36380Y-655636D02*
Y-660151D01*
X-36067Y-661096D01*
X-35440Y-661726D01*
X-34657Y-661936D01*
X-33874Y-661726D01*
X-33247Y-661096D01*
X-32934Y-660151D01*
Y-655636D01*
G01X-26790Y-661936D02*
X-29924D01*
Y-655636D01*
X-26790D01*
G01X-28044Y-658681D02*
X-29924D01*
G01X-22997Y-655636D02*
X-21117D01*
G01X-22057D02*
Y-661936D01*
G01X-22997D02*
X-21117D01*
G01X-11102Y-661096D02*
X-10475Y-661621D01*
X-9770Y-661936D01*
X-9144D01*
X-8517Y-661621D01*
X-8047Y-661096D01*
X-7812Y-660361D01*
X-7969Y-659626D01*
X-8360Y-658996D01*
X-9065Y-658576D01*
X-10005Y-658366D01*
X-10554Y-657946D01*
X-10789Y-657211D01*
X-10632Y-656476D01*
X-10240Y-655951D01*
X-9692Y-655636D01*
X-9144D01*
X-8595Y-655846D01*
X-8125Y-656371D01*
G01X-4802Y-661936D02*
Y-655636D01*
G01X-1512D02*
Y-661936D01*
G01Y-658786D02*
X-4802D01*
G01X1185Y-661936D02*
X3143Y-655636D01*
X5101Y-661936D01*
G01X4396Y-659731D02*
X1890D01*
G01X7641Y-661936D02*
Y-655636D01*
X11245Y-661936D01*
Y-655636D01*
G01X20398Y-661936D02*
Y-655636D01*
G01X23688D02*
Y-661936D01*
G01Y-658786D02*
X20398D01*
G01X26698Y-661096D02*
X27325Y-661621D01*
X28030Y-661936D01*
X28656D01*
X29283Y-661621D01*
X29753Y-661096D01*
X29988Y-660361D01*
X29831Y-659626D01*
X29440Y-658996D01*
X28735Y-658576D01*
X27795Y-658366D01*
X27246Y-657946D01*
X27011Y-657211D01*
X27168Y-656476D01*
X27560Y-655951D01*
X28108Y-655636D01*
X28656D01*
X29205Y-655846D01*
X29675Y-656371D01*
G01X33703Y-655636D02*
X35583D01*
G01X34643D02*
Y-661936D01*
G01X33703D02*
X35583D01*
G01X38985D02*
X40943Y-655636D01*
X42901Y-661936D01*
G01X42196Y-659731D02*
X39690D01*
G01X45441Y-661936D02*
Y-655636D01*
X49045Y-661936D01*
Y-655636D01*
G01X54013Y-658786D02*
X55580D01*
Y-660676D01*
X55110Y-661306D01*
X54561Y-661726D01*
X53778Y-661936D01*
X52995Y-661726D01*
X52446Y-661306D01*
X51976Y-660676D01*
X51663Y-659941D01*
X51506Y-659101D01*
Y-658366D01*
X51663Y-657736D01*
X51976Y-657001D01*
X52446Y-656371D01*
X52916Y-655951D01*
X53543Y-655636D01*
X54091D01*
X54718Y-655846D01*
X55188Y-656266D01*
G01X59686Y-663091D02*
X60000Y-661726D01*
G01X66143Y-655636D02*
Y-661936D01*
G01X64341Y-655636D02*
X67945D01*
G01X70485Y-661936D02*
X72443Y-655636D01*
X74401Y-661936D01*
G01X73696Y-659731D02*
X71190D01*
G01X78743Y-661936D02*
X78116Y-661831D01*
X77568Y-661411D01*
X77098Y-660781D01*
X76785Y-660046D01*
X76628Y-659206D01*
Y-658366D01*
X76785Y-657526D01*
X77098Y-656791D01*
X77568Y-656161D01*
X78116Y-655741D01*
X78743Y-655636D01*
X79370Y-655741D01*
X79918Y-656161D01*
X80388Y-656791D01*
X80701Y-657526D01*
X80858Y-658366D01*
Y-659206D01*
X80701Y-660046D01*
X80388Y-660781D01*
X79918Y-661411D01*
X79370Y-661831D01*
X78743Y-661936D01*
G01X91343D02*
Y-659101D01*
X89776Y-655636D01*
G01X92910D02*
X91343Y-659101D01*
G01X95920Y-655636D02*
Y-660151D01*
X96233Y-661096D01*
X96860Y-661726D01*
X97643Y-661936D01*
X98426Y-661726D01*
X99053Y-661096D01*
X99366Y-660151D01*
Y-655636D01*
G01X101985Y-661936D02*
X103943Y-655636D01*
X105901Y-661936D01*
G01X105196Y-659731D02*
X102690D01*
G01X108441Y-661936D02*
Y-655636D01*
X112045Y-661936D01*
Y-655636D01*
G01X-42759Y-651936D02*
Y-645636D01*
X-39155Y-651936D01*
Y-645636D01*
G01X-34657Y-651936D02*
X-35284Y-651831D01*
X-35832Y-651411D01*
X-36302Y-650781D01*
X-36615Y-650046D01*
X-36772Y-649206D01*
Y-648366D01*
X-36615Y-647526D01*
X-36302Y-646791D01*
X-35832Y-646161D01*
X-35284Y-645741D01*
X-34657Y-645636D01*
X-34030Y-645741D01*
X-33482Y-646161D01*
X-33012Y-646791D01*
X-32699Y-647526D01*
X-32542Y-648366D01*
Y-649206D01*
X-32699Y-650046D01*
X-33012Y-650781D01*
X-33482Y-651411D01*
X-34030Y-651831D01*
X-34657Y-651936D01*
G01X-28357Y-652146D02*
X-28514Y-652041D01*
Y-651831D01*
X-28357Y-651726D01*
X-28200Y-651831D01*
Y-652041D01*
X-28357Y-652146D01*
G01X-22057Y-651936D02*
Y-645636D01*
X-22997Y-646896D01*
G01Y-651936D02*
X-21117D01*
G01X-15757D02*
X-15209Y-651831D01*
X-14582Y-651516D01*
X-14190Y-650991D01*
X-14034Y-650256D01*
X-14190Y-649521D01*
X-14660Y-648891D01*
X-15365Y-648576D01*
X-16149D01*
X-16619Y-648366D01*
X-17010Y-647841D01*
X-17167Y-647106D01*
X-16932Y-646371D01*
X-16384Y-645846D01*
X-15757Y-645636D01*
X-15130Y-645846D01*
X-14582Y-646371D01*
X-14347Y-647106D01*
X-14504Y-647841D01*
X-14895Y-648366D01*
X-15365Y-648576D01*
X-16149D01*
X-16854Y-648891D01*
X-17324Y-649521D01*
X-17480Y-650256D01*
X-17324Y-650991D01*
X-16932Y-651516D01*
X-16305Y-651831D01*
X-15757Y-651936D01*
G01X-9457D02*
X-8909Y-651831D01*
X-8282Y-651516D01*
X-7890Y-650991D01*
X-7734Y-650256D01*
X-7890Y-649521D01*
X-8360Y-648891D01*
X-9065Y-648576D01*
X-9849D01*
X-10319Y-648366D01*
X-10710Y-647841D01*
X-10867Y-647106D01*
X-10632Y-646371D01*
X-10084Y-645846D01*
X-9457Y-645636D01*
X-8830Y-645846D01*
X-8282Y-646371D01*
X-8047Y-647106D01*
X-8204Y-647841D01*
X-8595Y-648366D01*
X-9065Y-648576D01*
X-9849D01*
X-10554Y-648891D01*
X-11024Y-649521D01*
X-11180Y-650256D01*
X-11024Y-650991D01*
X-10632Y-651516D01*
X-10005Y-651831D01*
X-9457Y-651936D01*
G01X-3314Y-653091D02*
X-3000Y-651726D01*
G01X793Y-645636D02*
X1890Y-651936D01*
X3143Y-645636D01*
X4396Y-651936D01*
X5493Y-645636D01*
G01X11010Y-651936D02*
X7876D01*
Y-645636D01*
X11010D01*
G01X9756Y-648681D02*
X7876D01*
G01X13941Y-651936D02*
Y-645636D01*
X17545Y-651936D01*
Y-645636D01*
G01X26698Y-651936D02*
Y-645636D01*
G01X29988D02*
Y-651936D01*
G01Y-648786D02*
X26698D01*
G01X32293Y-645636D02*
X33390Y-651936D01*
X34643Y-645636D01*
X35896Y-651936D01*
X36993Y-645636D01*
G01X38985Y-651936D02*
X40943Y-645636D01*
X42901Y-651936D01*
G01X42196Y-649731D02*
X39690D01*
G01X52055Y-646686D02*
X52525Y-646056D01*
X53073Y-645741D01*
X53700Y-645636D01*
X54483Y-645846D01*
X55031Y-646371D01*
X55188Y-647001D01*
X55110Y-647631D01*
X54796Y-648156D01*
X53230Y-649206D01*
X52525Y-649941D01*
X52055Y-650991D01*
X51898Y-651936D01*
X55188D01*
G01X58041D02*
Y-645636D01*
X61645Y-651936D01*
Y-645636D01*
G01X64420Y-651936D02*
Y-645636D01*
X65986D01*
X66613Y-645951D01*
X67083Y-646371D01*
X67475Y-647001D01*
X67788Y-647736D01*
X67866Y-648786D01*
X67788Y-649836D01*
X67475Y-650571D01*
X67083Y-651201D01*
X66613Y-651621D01*
X65986Y-651936D01*
X64420D01*
G01X77176D02*
Y-645636D01*
X79135D01*
X79761Y-645951D01*
X80153Y-646371D01*
X80310Y-647211D01*
X80153Y-648051D01*
X79683Y-648576D01*
X79135Y-648891D01*
X77176D01*
G01X79135D02*
X80310Y-651936D01*
G01X83320D02*
Y-645636D01*
X84886D01*
X85513Y-645951D01*
X85983Y-646371D01*
X86375Y-647001D01*
X86688Y-647736D01*
X86766Y-648786D01*
X86688Y-649836D01*
X86375Y-650571D01*
X85983Y-651201D01*
X85513Y-651621D01*
X84886Y-651936D01*
X83320D01*
G01X91343Y-652146D02*
X91186Y-652041D01*
Y-651831D01*
X91343Y-651726D01*
X91500Y-651831D01*
Y-652041D01*
X91343Y-652146D01*
G01X-18657Y-639236D02*
X-21177Y-638819D01*
X-23382Y-637153D01*
X-25272Y-634653D01*
X-26532Y-631736D01*
X-27162Y-628403D01*
Y-625069D01*
X-26532Y-621736D01*
X-25272Y-618819D01*
X-23382Y-616320D01*
X-21177Y-614653D01*
X-18657Y-614236D01*
X-16137Y-614653D01*
X-13932Y-616320D01*
X-12042Y-618819D01*
X-10782Y-621736D01*
X-10152Y-625069D01*
Y-628403D01*
X-10782Y-631736D01*
X-12042Y-634653D01*
X-13932Y-637153D01*
X-16137Y-638819D01*
X-18657Y-639236D01*
G01X-16137Y-632569D02*
X-12357Y-639236D01*
G01X1188Y-622570D02*
Y-634236D01*
X2448Y-637153D01*
X4338Y-638819D01*
X6543Y-639236D01*
X8748Y-638819D01*
X10638Y-637153D01*
X11898Y-634236D01*
G01Y-639236D02*
Y-622570D01*
G01X37413Y-639236D02*
Y-622570D01*
G01Y-625486D02*
X36153Y-623820D01*
X34263Y-622986D01*
X32058Y-622570D01*
X29853Y-623403D01*
X27963Y-625069D01*
X26703Y-627570D01*
X26073Y-630903D01*
X26703Y-634236D01*
X27963Y-636737D01*
X29853Y-638403D01*
X32058Y-639236D01*
X34263Y-638819D01*
X36153Y-637570D01*
X37413Y-635903D01*
G01X51588Y-639236D02*
Y-622570D01*
G01Y-626736D02*
X52848Y-624653D01*
X54738Y-622986D01*
X57258Y-622570D01*
X59463Y-622986D01*
X61353Y-624653D01*
X62298Y-627570D01*
Y-639236D01*
G01X82143Y-614236D02*
Y-639236D01*
G01X77733Y-622570D02*
X86553D01*
G01X113013Y-639236D02*
Y-622570D01*
G01Y-625486D02*
X111753Y-623820D01*
X109863Y-622986D01*
X107658Y-622570D01*
X105453Y-623403D01*
X103563Y-625069D01*
X102303Y-627570D01*
X101673Y-630903D01*
X102303Y-634236D01*
X103563Y-636737D01*
X105453Y-638403D01*
X107658Y-639236D01*
X109863Y-638819D01*
X111753Y-637570D01*
X113013Y-635903D01*
G01X152693Y-618936D02*
Y-626936D01*
X156693D01*
G01X164493D02*
Y-621603D01*
G01Y-622536D02*
X164093Y-622003D01*
X163493Y-621736D01*
X162793Y-621603D01*
X162093Y-621869D01*
X161493Y-622403D01*
X161093Y-623203D01*
X160893Y-624269D01*
X161093Y-625336D01*
X161493Y-626136D01*
X162093Y-626669D01*
X162793Y-626936D01*
X163493Y-626803D01*
X164093Y-626403D01*
X164493Y-625870D01*
G01X168593Y-629336D02*
X169193Y-629603D01*
X169993Y-629336D01*
X170493Y-628803D01*
X170893Y-628136D01*
X171493Y-626003D01*
X172793Y-621603D01*
G01X169593D02*
X171493Y-626003D01*
G01X177193Y-623336D02*
X180393D01*
X180093Y-622403D01*
X179593Y-621869D01*
X178893Y-621603D01*
X178193Y-621736D01*
X177593Y-622136D01*
X177193Y-623069D01*
X176993Y-623870D01*
Y-624669D01*
X177193Y-625469D01*
X177693Y-626269D01*
X178293Y-626803D01*
X178993Y-626936D01*
X179693Y-626669D01*
X180393Y-625870D01*
G01X185293Y-626936D02*
Y-621603D01*
G01Y-622669D02*
X185793Y-622136D01*
X186293Y-621736D01*
X186993Y-621603D01*
X187493Y-621736D01*
X188093Y-622136D01*
G01X173993Y-676936D02*
Y-668936D01*
G01X177793D02*
X173993Y-673870D01*
G01X178393Y-676936D02*
X175693Y-671603D01*
G01X185993Y-676936D02*
Y-671603D01*
G01Y-672536D02*
X185593Y-672003D01*
X184993Y-671736D01*
X184293Y-671603D01*
X183593Y-671869D01*
X182993Y-672403D01*
X182593Y-673203D01*
X182393Y-674269D01*
X182593Y-675336D01*
X182993Y-676136D01*
X183593Y-676669D01*
X184293Y-676936D01*
X184993Y-676803D01*
X185593Y-676403D01*
X185993Y-675870D01*
G01X192193Y-671603D02*
Y-676936D01*
G01Y-669469D02*
X191993Y-669336D01*
Y-669069D01*
X192193Y-668936D01*
X192393Y-669069D01*
Y-669336D01*
X192193Y-669469D01*
G01X176993Y-647669D02*
X177393Y-647269D01*
X177693Y-646603D01*
X177893Y-645669D01*
X177693Y-644869D01*
X177293Y-644336D01*
X176593Y-643936D01*
X173893D01*
Y-651936D01*
X177193D01*
X177893Y-651403D01*
X178293Y-650603D01*
X178493Y-649669D01*
X178293Y-648736D01*
X177693Y-647936D01*
X176993Y-647669D01*
X173893D01*
G01X184193Y-651936D02*
X183393Y-651803D01*
X182693Y-651269D01*
X182093Y-650469D01*
X181693Y-649536D01*
X181493Y-648469D01*
Y-647403D01*
X181693Y-646336D01*
X182093Y-645403D01*
X182693Y-644603D01*
X183393Y-644069D01*
X184193Y-643936D01*
X184993Y-644069D01*
X185693Y-644603D01*
X186293Y-645403D01*
X186693Y-646336D01*
X186893Y-647403D01*
Y-648469D01*
X186693Y-649536D01*
X186293Y-650469D01*
X185693Y-651269D01*
X184993Y-651803D01*
X184193Y-651936D01*
G01X192193Y-643936D02*
Y-651936D01*
G01X189893Y-643936D02*
X194493D01*
G01X200193D02*
Y-651936D01*
G01X197893Y-643936D02*
X202493D01*
G01X208193Y-651936D02*
X207393Y-651803D01*
X206693Y-651269D01*
X206093Y-650469D01*
X205693Y-649536D01*
X205493Y-648469D01*
Y-647403D01*
X205693Y-646336D01*
X206093Y-645403D01*
X206693Y-644603D01*
X207393Y-644069D01*
X208193Y-643936D01*
X208993Y-644069D01*
X209693Y-644603D01*
X210293Y-645403D01*
X210693Y-646336D01*
X210893Y-647403D01*
Y-648469D01*
X210693Y-649536D01*
X210293Y-650469D01*
X209693Y-651269D01*
X208993Y-651803D01*
X208193Y-651936D01*
G01X213593D02*
Y-643936D01*
X216193Y-650603D01*
X218793Y-643936D01*
Y-651936D01*
G01X206193Y-626936D02*
Y-618936D01*
X204993Y-620536D01*
G01Y-626936D02*
X207393D01*
G01X212293Y-620269D02*
X212893Y-619469D01*
X213593Y-619069D01*
X214393Y-618936D01*
X215393Y-619203D01*
X216093Y-619869D01*
X216293Y-620669D01*
X216193Y-621470D01*
X215793Y-622136D01*
X213793Y-623469D01*
X212893Y-624403D01*
X212293Y-625736D01*
X212093Y-626936D01*
X216293D01*
G01X279293Y-670269D02*
X279893Y-669469D01*
X280593Y-669069D01*
X281393Y-668936D01*
X282393Y-669203D01*
X283093Y-669869D01*
X283293Y-670669D01*
X283193Y-671470D01*
X282793Y-672136D01*
X280793Y-673469D01*
X279893Y-674403D01*
X279293Y-675736D01*
X279093Y-676936D01*
X283293D01*
G01X289193Y-668936D02*
X288393Y-669203D01*
X287793Y-669869D01*
X287393Y-670669D01*
X287093Y-671736D01*
X286993Y-672936D01*
X287093Y-674136D01*
X287393Y-675203D01*
X287793Y-676003D01*
X288393Y-676669D01*
X289193Y-676936D01*
X289993Y-676669D01*
X290593Y-676003D01*
X290993Y-675203D01*
X291293Y-674136D01*
X291393Y-672936D01*
X291293Y-671736D01*
X290993Y-670669D01*
X290593Y-669869D01*
X289993Y-669203D01*
X289193Y-668936D01*
G01X295293Y-670269D02*
X295893Y-669469D01*
X296593Y-669069D01*
X297393Y-668936D01*
X298393Y-669203D01*
X299093Y-669869D01*
X299293Y-670669D01*
X299193Y-671470D01*
X298793Y-672136D01*
X296793Y-673469D01*
X295893Y-674403D01*
X295293Y-675736D01*
X295093Y-676936D01*
X299293D01*
G01X303293Y-670269D02*
X303893Y-669469D01*
X304593Y-669069D01*
X305393Y-668936D01*
X306393Y-669203D01*
X307093Y-669869D01*
X307293Y-670669D01*
X307193Y-671470D01*
X306793Y-672136D01*
X304793Y-673469D01*
X303893Y-674403D01*
X303293Y-675736D01*
X303093Y-676936D01*
X307293D01*
G01X311393Y-677203D02*
X314993Y-668936D01*
G01X321193Y-676936D02*
Y-668936D01*
X319993Y-670536D01*
G01Y-676936D02*
X322393D01*
G01X327293Y-670269D02*
X327893Y-669469D01*
X328593Y-669069D01*
X329393Y-668936D01*
X330393Y-669203D01*
X331093Y-669869D01*
X331293Y-670669D01*
X331193Y-671470D01*
X330793Y-672136D01*
X328793Y-673469D01*
X327893Y-674403D01*
X327293Y-675736D01*
X327093Y-676936D01*
X331293D01*
G01X335393Y-677203D02*
X338993Y-668936D01*
G01X345193D02*
X344393Y-669203D01*
X343793Y-669869D01*
X343393Y-670669D01*
X343093Y-671736D01*
X342993Y-672936D01*
X343093Y-674136D01*
X343393Y-675203D01*
X343793Y-676003D01*
X344393Y-676669D01*
X345193Y-676936D01*
X345993Y-676669D01*
X346593Y-676003D01*
X346993Y-675203D01*
X347293Y-674136D01*
X347393Y-672936D01*
X347293Y-671736D01*
X346993Y-670669D01*
X346593Y-669869D01*
X345993Y-669203D01*
X345193Y-668936D01*
G01X351493Y-676003D02*
X352193Y-676669D01*
X352993Y-676936D01*
X353793Y-676669D01*
X354493Y-675870D01*
X354993Y-674669D01*
X355193Y-673469D01*
Y-672003D01*
X354993Y-670803D01*
X354493Y-669736D01*
X353893Y-669203D01*
X353193Y-668936D01*
X352393Y-669203D01*
X351793Y-669736D01*
X351393Y-670536D01*
X351193Y-671603D01*
X351393Y-672536D01*
X351893Y-673469D01*
X352493Y-674003D01*
X353193Y-674136D01*
X353993Y-673870D01*
X354593Y-673203D01*
X355193Y-672003D01*
G01X278993Y-651936D02*
Y-643936D01*
X280993D01*
X281793Y-644336D01*
X282393Y-644869D01*
X282893Y-645669D01*
X283293Y-646603D01*
X283393Y-647936D01*
X283293Y-649269D01*
X282893Y-650203D01*
X282393Y-651003D01*
X281793Y-651536D01*
X280993Y-651936D01*
X278993D01*
G01X286693D02*
X289193Y-643936D01*
X291693Y-651936D01*
G01X290793Y-649136D02*
X287593D01*
G01X297193Y-643936D02*
X296393Y-644203D01*
X295793Y-644869D01*
X295393Y-645669D01*
X295093Y-646736D01*
X294993Y-647936D01*
X295093Y-649136D01*
X295393Y-650203D01*
X295793Y-651003D01*
X296393Y-651669D01*
X297193Y-651936D01*
X297993Y-651669D01*
X298593Y-651003D01*
X298993Y-650203D01*
X299293Y-649136D01*
X299393Y-647936D01*
X299293Y-646736D01*
X298993Y-645669D01*
X298593Y-644869D01*
X297993Y-644203D01*
X297193Y-643936D01*
G01X303293Y-651936D02*
Y-643936D01*
X307093D01*
G01X305693Y-647803D02*
X303293D01*
G01X313193Y-643936D02*
X312393Y-644203D01*
X311793Y-644869D01*
X311393Y-645669D01*
X311093Y-646736D01*
X310993Y-647936D01*
X311093Y-649136D01*
X311393Y-650203D01*
X311793Y-651003D01*
X312393Y-651669D01*
X313193Y-651936D01*
X313993Y-651669D01*
X314593Y-651003D01*
X314993Y-650203D01*
X315293Y-649136D01*
X315393Y-647936D01*
X315293Y-646736D01*
X314993Y-645669D01*
X314593Y-644869D01*
X313993Y-644203D01*
X313193Y-643936D01*
G01X321193D02*
Y-651936D01*
G01X318893Y-643936D02*
X323493D01*
G01X326593Y-651936D02*
Y-643936D01*
X329193Y-650603D01*
X331793Y-643936D01*
Y-651936D01*
G01X334993D02*
Y-643936D01*
X336993D01*
X337793Y-644336D01*
X338393Y-644869D01*
X338893Y-645669D01*
X339293Y-646603D01*
X339393Y-647936D01*
X339293Y-649269D01*
X338893Y-650203D01*
X338393Y-651003D01*
X337793Y-651536D01*
X336993Y-651936D01*
X334993D01*
G01X347393Y-644603D02*
X346793Y-644203D01*
X346093Y-643936D01*
X345293D01*
X344393Y-644336D01*
X343693Y-645003D01*
X343193Y-645803D01*
X342793Y-647136D01*
X342693Y-648336D01*
X342893Y-649536D01*
X343193Y-650336D01*
X343793Y-651136D01*
X344493Y-651669D01*
X345193Y-651936D01*
X345893D01*
X346593Y-651669D01*
X347193Y-651269D01*
X347693Y-650736D01*
G01X350993Y-651936D02*
Y-643936D01*
X352993D01*
X353793Y-644336D01*
X354393Y-644869D01*
X354893Y-645669D01*
X355293Y-646603D01*
X355393Y-647936D01*
X355293Y-649269D01*
X354893Y-650203D01*
X354393Y-651003D01*
X353793Y-651536D01*
X352993Y-651936D01*
X350993D01*
G01X361193Y-643936D02*
X360393Y-644203D01*
X359793Y-644869D01*
X359393Y-645669D01*
X359093Y-646736D01*
X358993Y-647936D01*
X359093Y-649136D01*
X359393Y-650203D01*
X359793Y-651003D01*
X360393Y-651669D01*
X361193Y-651936D01*
X361993Y-651669D01*
X362593Y-651003D01*
X362993Y-650203D01*
X363293Y-649136D01*
X363393Y-647936D01*
X363293Y-646736D01*
X362993Y-645669D01*
X362593Y-644869D01*
X361993Y-644203D01*
X361193Y-643936D01*
G01X298418Y-624819D02*
Y-618519D01*
X301394D01*
G01X300298Y-621564D02*
X298418D01*
G01X306206Y-618519D02*
X305579Y-618729D01*
X305109Y-619254D01*
X304796Y-619884D01*
X304561Y-620724D01*
X304483Y-621669D01*
X304561Y-622614D01*
X304796Y-623454D01*
X305109Y-624084D01*
X305579Y-624609D01*
X306206Y-624819D01*
X306833Y-624609D01*
X307303Y-624084D01*
X307616Y-623454D01*
X307851Y-622614D01*
X307929Y-621669D01*
X307851Y-620724D01*
X307616Y-619884D01*
X307303Y-619254D01*
X306833Y-618729D01*
X306206Y-618519D01*
G01X312506D02*
Y-624819D01*
G01X310704Y-618519D02*
X314308D01*
G01X316456Y-626919D02*
X321156D01*
G01X323069Y-624819D02*
Y-618519D01*
X325106Y-623769D01*
X327143Y-618519D01*
Y-624819D01*
G01X332816D02*
Y-620619D01*
G01Y-621354D02*
X332503Y-620934D01*
X332033Y-620724D01*
X331484Y-620619D01*
X330936Y-620829D01*
X330466Y-621249D01*
X330153Y-621879D01*
X329996Y-622719D01*
X330153Y-623559D01*
X330466Y-624189D01*
X330936Y-624609D01*
X331484Y-624819D01*
X332033Y-624714D01*
X332503Y-624399D01*
X332816Y-623979D01*
G01X336374Y-624819D02*
Y-620619D01*
G01Y-621669D02*
X336688Y-621144D01*
X337158Y-620724D01*
X337784Y-620619D01*
X338333Y-620724D01*
X338803Y-621144D01*
X339038Y-621879D01*
Y-624819D01*
G01X345416D02*
Y-620619D01*
G01Y-621354D02*
X345103Y-620934D01*
X344633Y-620724D01*
X344084Y-620619D01*
X343536Y-620829D01*
X343066Y-621249D01*
X342753Y-621879D01*
X342596Y-622719D01*
X342753Y-623559D01*
X343066Y-624189D01*
X343536Y-624609D01*
X344084Y-624819D01*
X344633Y-624714D01*
X345103Y-624399D01*
X345416Y-623979D01*
G01X349209Y-626394D02*
X349758Y-626814D01*
X350384Y-626919D01*
X350933Y-626814D01*
X351403Y-626289D01*
X351716Y-625554D01*
Y-620619D01*
G01Y-621459D02*
X351403Y-621039D01*
X350933Y-620724D01*
X350384Y-620619D01*
X349758Y-620829D01*
X349366Y-621249D01*
X349053Y-621984D01*
X348896Y-622719D01*
X348974Y-623349D01*
X349288Y-624084D01*
X349758Y-624609D01*
X350384Y-624819D01*
X350854Y-624714D01*
X351403Y-624294D01*
X351716Y-623874D01*
G01X355431Y-621984D02*
X357938D01*
X357703Y-621249D01*
X357311Y-620829D01*
X356763Y-620619D01*
X356214Y-620724D01*
X355744Y-621039D01*
X355431Y-621774D01*
X355274Y-622404D01*
Y-623034D01*
X355431Y-623664D01*
X355823Y-624294D01*
X356293Y-624714D01*
X356841Y-624819D01*
X357389Y-624609D01*
X357938Y-623979D01*
G01X360556Y-624819D02*
Y-620619D01*
G01Y-621774D02*
X360791Y-621249D01*
X361183Y-620829D01*
X361731Y-620619D01*
X362279Y-620829D01*
X362671Y-621249D01*
X362906Y-621774D01*
Y-624819D01*
G01Y-621774D02*
X363141Y-621249D01*
X363533Y-620829D01*
X364081Y-620619D01*
X364629Y-620829D01*
X365021Y-621249D01*
X365256Y-621879D01*
Y-624819D01*
G01X368031Y-621984D02*
X370538D01*
X370303Y-621249D01*
X369911Y-620829D01*
X369363Y-620619D01*
X368814Y-620724D01*
X368344Y-621039D01*
X368031Y-621774D01*
X367874Y-622404D01*
Y-623034D01*
X368031Y-623664D01*
X368423Y-624294D01*
X368893Y-624714D01*
X369441Y-624819D01*
X369989Y-624609D01*
X370538Y-623979D01*
G01X374174Y-624819D02*
Y-620619D01*
G01Y-621669D02*
X374488Y-621144D01*
X374958Y-620724D01*
X375584Y-620619D01*
X376133Y-620724D01*
X376603Y-621144D01*
X376838Y-621879D01*
Y-624819D01*
G01X381806Y-618519D02*
Y-624819D01*
G01X380709Y-620619D02*
X382903D01*
G01X385756Y-626919D02*
X390456D01*
G01X395033Y-621459D02*
X395346Y-621144D01*
X395581Y-620619D01*
X395738Y-619884D01*
X395581Y-619254D01*
X395268Y-618834D01*
X394719Y-618519D01*
X392604D01*
Y-624819D01*
X395189D01*
X395738Y-624399D01*
X396051Y-623769D01*
X396208Y-623034D01*
X396051Y-622299D01*
X395581Y-621669D01*
X395033Y-621459D01*
X392604D01*
G01X398983Y-624819D02*
Y-618519D01*
X400549D01*
X401176Y-618834D01*
X401646Y-619254D01*
X402038Y-619884D01*
X402351Y-620619D01*
X402429Y-621669D01*
X402351Y-622719D01*
X402038Y-623454D01*
X401646Y-624084D01*
X401176Y-624504D01*
X400549Y-624819D01*
X398983D01*
G01X367693Y-679936D02*
Y-671936D01*
X366493Y-673536D01*
G01Y-679936D02*
X368893D01*
G01X373793Y-676603D02*
X374493Y-675669D01*
X375093Y-675136D01*
X375893Y-674869D01*
X376593Y-675136D01*
X377093Y-675669D01*
X377493Y-676469D01*
X377593Y-677403D01*
X377493Y-678203D01*
X377093Y-679003D01*
X376493Y-679669D01*
X375793Y-679936D01*
X374993Y-679669D01*
X374293Y-678870D01*
X373893Y-677669D01*
X373793Y-676336D01*
X373993Y-674603D01*
X374293Y-673669D01*
X374793Y-672736D01*
X375493Y-672069D01*
X376193Y-671936D01*
X376893Y-672203D01*
X377393Y-672869D01*
G01X383693Y-680203D02*
X383493Y-680069D01*
Y-679803D01*
X383693Y-679669D01*
X383893Y-679803D01*
Y-680069D01*
X383693Y-680203D01*
G01X389793Y-676603D02*
X390493Y-675669D01*
X391093Y-675136D01*
X391893Y-674869D01*
X392593Y-675136D01*
X393093Y-675669D01*
X393493Y-676469D01*
X393593Y-677403D01*
X393493Y-678203D01*
X393093Y-679003D01*
X392493Y-679669D01*
X391793Y-679936D01*
X390993Y-679669D01*
X390293Y-678870D01*
X389893Y-677669D01*
X389793Y-676336D01*
X389993Y-674603D01*
X390293Y-673669D01*
X390793Y-672736D01*
X391493Y-672069D01*
X392193Y-671936D01*
X392893Y-672203D01*
X393393Y-672869D01*
G01X412693Y-679936D02*
Y-671936D01*
X411493Y-673536D01*
G01Y-679936D02*
X413893D01*
G01X420493D02*
X420693Y-678203D01*
X420993Y-676736D01*
X421393Y-675403D01*
X421893Y-673936D01*
X422693Y-671936D01*
X418693D01*
G01X428693Y-680203D02*
X428493Y-680069D01*
Y-679803D01*
X428693Y-679669D01*
X428893Y-679803D01*
Y-680069D01*
X428693Y-680203D01*
G01X434793Y-673269D02*
X435393Y-672469D01*
X436093Y-672069D01*
X436893Y-671936D01*
X437893Y-672203D01*
X438593Y-672869D01*
X438793Y-673669D01*
X438693Y-674470D01*
X438293Y-675136D01*
X436293Y-676469D01*
X435393Y-677403D01*
X434793Y-678736D01*
X434593Y-679936D01*
X438793D01*
G01X432493Y-654936D02*
Y-646936D01*
X434493D01*
X435293Y-647336D01*
X435893Y-647869D01*
X436393Y-648669D01*
X436793Y-649603D01*
X436893Y-650936D01*
X436793Y-652269D01*
X436393Y-653203D01*
X435893Y-654003D01*
X435293Y-654536D01*
X434493Y-654936D01*
X432493D01*
G54D39*
X57937Y391577D03*
G36*
G01X117915Y183421D02*
G02X92715I-12600J0D01*
G01Y186566D01*
X97005D01*
Y183421D01*
G03X113625I8310J0D01*
G01Y189721D01*
G03X97005I-8310J0D01*
G01Y186576D01*
X92715D01*
Y189721D01*
G02X117915I12600J0D01*
G01Y183421D01*
G37*
G54D75*
X236220Y424016D03*
X301181D03*
G54D57*
X122000Y269437D03*
X119441D03*
Y261563D03*
X122000D03*
X124559Y269437D03*
Y261563D03*
X137059Y269437D03*
X134500D03*
X131941D03*
Y261563D03*
X134500D03*
X137059D03*
G54D84*
X441000Y-454000D03*
X451000D03*
Y-345000D03*
X441000D03*
Y-333400D03*
X451000D03*
Y-235000D03*
X441000D03*
X451000Y-225000D03*
X441000D03*
Y-126600D03*
X451000D03*
Y-117000D03*
X441000D03*
Y-8000D03*
X451000D03*
X441000Y2000D03*
X451000D03*
Y106000D03*
X441000D03*
Y116000D03*
X451000D03*
Y210000D03*
X441000D03*
X451000Y220000D03*
X441000D03*
Y314000D03*
X451000D03*
Y326000D03*
X441000D03*
Y430000D03*
X451000D03*
G54D66*
X155205Y52677D03*
G54D94*
G01X376620Y-440713D02*
X375904Y-438145D01*
G01X376680Y-213391D02*
X375964Y-215959D01*
G01X378588Y-440713D02*
X379304Y-438145D01*
G01X378648Y-213391D02*
X379364Y-215959D01*
G01X397708Y-466775D02*
X396992Y-464207D01*
G01X399676Y-466775D02*
X400392Y-464207D01*
G01X397796Y-118453D02*
X397080Y-121021D01*
G01X399764Y-118453D02*
X400480Y-121021D01*
G54D85*
G01X70313Y354280D02*
Y353987D01*
X71576Y352724D01*
X71624D01*
G01D02*
X71906D01*
G01X70312Y351130D02*
Y351412D01*
X71624Y352724D01*
G01X68757Y355873D02*
X70313Y357429D01*
G01X73462Y376327D02*
X73500D01*
X75056Y377883D01*
G01X78206Y362173D02*
Y362179D01*
X79852Y363825D01*
G01X78206Y374733D02*
X76664Y376275D01*
Y376425D01*
G01X78206Y365322D02*
Y365006D01*
X76929Y363729D01*
X76612D01*
G01X78206Y371584D02*
X77784D01*
X76589Y370389D01*
Y370000D01*
G01X70332Y382607D02*
X68757Y384182D01*
G01X75056Y377883D02*
Y378291D01*
X76340Y379575D01*
X76664D01*
G01X75056Y377883D02*
X73482Y379457D01*
Y379476D01*
G01X71906Y384182D02*
X74649Y386925D01*
X75000D01*
G01X73482Y382626D02*
X73462D01*
X71906Y384182D01*
G01X87617Y362173D02*
X89210Y360580D01*
Y360579D01*
G01X90766Y374733D02*
X90971Y374528D01*
X93711D01*
G01X81355Y362173D02*
X81507Y362325D01*
X83864D01*
G01X89210Y376327D02*
X88927D01*
X87617Y375017D01*
G01D02*
Y374733D01*
G01X86061Y376327D02*
X86473D01*
X87617Y375183D01*
Y375017D01*
G01X81355Y374733D02*
Y375327D01*
X82355Y376327D01*
X82911D01*
G01D02*
X86061D01*
G01X106564Y346400D02*
X104983Y347981D01*
X104958D01*
G01X106575Y357500D02*
Y355896D01*
X104959Y354280D01*
G01D02*
X104715Y354036D01*
Y351978D01*
X104958Y351735D01*
Y351131D01*
G01X100215Y352724D02*
X100675D01*
X101809Y351590D01*
Y351130D01*
G01X103383Y349556D02*
X103884Y350057D01*
Y350099D01*
X104340Y350806D01*
X104633D01*
X104958Y351131D01*
G01X97066Y352724D02*
X98659Y351131D01*
Y351130D01*
G01X104000Y360925D02*
X103425Y360350D01*
Y357500D01*
G01D02*
X101842D01*
X100215Y355873D01*
G01D02*
X101808Y354280D01*
X101809D01*
G01X95510Y382626D02*
X97066Y384182D01*
G01D02*
Y383834D01*
X98275Y382625D01*
X98664D01*
G01X134500Y261563D02*
Y259796D01*
X136096Y258200D01*
X139300D01*
X140500Y259400D01*
Y265399D01*
X141816Y266715D01*
X142665D01*
X142780Y266830D01*
G01X154842Y365153D02*
X148428D01*
X148050Y364775D01*
G01X154842Y363185D02*
X150484D01*
X148924Y361625D01*
X148050D01*
G01X163646Y190725D02*
X163398Y190477D01*
X161240D01*
G01X163800Y356800D02*
Y357300D01*
X164094Y357594D01*
Y359838D01*
G01X161300Y354600D02*
Y356293D01*
X162126Y358288D01*
Y359838D01*
G01X171378Y365153D02*
X174054D01*
X174776Y365875D01*
X177500D01*
G01X171378Y363185D02*
X174416D01*
X174876Y362725D01*
X177500D01*
G01X241300Y210104D02*
X241552D01*
X244500Y213052D01*
Y213425D01*
G01X252374Y134794D02*
Y132159D01*
G01X294600Y106900D02*
Y100110D01*
X290840Y96350D01*
G01D02*
X294175D01*
X295425Y97600D01*
G01X298575D02*
Y101900D01*
G01X295825Y116300D02*
X293829D01*
X293739Y116390D01*
X291360D01*
G01D02*
Y114040D01*
X293600Y111800D01*
X294800D01*
G01X298975Y116300D02*
Y118900D01*
G01X301000Y121016D02*
X304909D01*
X305000Y120925D01*
G01X296075Y126500D02*
Y122000D01*
G01D02*
X295075Y121000D01*
Y119100D01*
G01X303425Y131290D02*
X302035Y129900D01*
X301000D01*
G01X293125Y131700D02*
X291100D01*
X290200Y130800D01*
Y129500D01*
G01X296275Y131700D02*
X298400Y129575D01*
Y127100D01*
X300500Y125000D01*
G01X292925Y126500D02*
X291025D01*
X290737Y126212D01*
X288280D01*
G01X315975Y122000D02*
Y119225D01*
X318000Y117200D01*
G01X312825Y122000D02*
Y123325D01*
X313800Y124300D01*
G01X310500Y115425D02*
X307375D01*
X306300Y116500D01*
X304000D01*
G01X310500Y118575D02*
X312925D01*
X315100Y116400D01*
G01X305000Y124075D02*
X305625D01*
X307400Y122300D01*
G01X307560Y128500D02*
Y128540D01*
X306575Y129525D01*
Y131290D01*
G01X336461Y283202D02*
X335366Y282107D01*
X312272D01*
G54D49*
X105316Y213343D03*
G54D67*
X166895Y291162D03*
X175713Y287225D03*
Y295099D03*
G54D58*
X115100Y402000D03*
X120900D03*
X148400Y129000D03*
X142600D03*
X148748Y220947D03*
X154548D03*
X165824Y217706D03*
X164300Y233100D03*
X171624Y217706D03*
X170100Y233100D03*
X256510Y384400D03*
X271812Y154663D03*
X270100Y170500D03*
X272100Y224500D03*
X262310Y384400D03*
X277300Y137400D03*
X283100D03*
X277612Y154663D03*
X275900Y170500D03*
X277900Y224500D03*
X281914Y218630D03*
X276114D03*
X291488Y137870D03*
X297288D03*
X327200Y120250D03*
X323611Y196486D03*
X329411D03*
X333000Y120250D03*
G54D76*
X286549Y103090D03*
Y105649D03*
Y108209D03*
Y110768D03*
X309935Y103090D03*
Y105649D03*
Y108209D03*
Y110768D03*
G54D95*
G01X181802Y238444D02*
X181894Y238536D01*
Y240154D01*
X181300Y240748D01*
Y242425D01*
G01X184890Y242440D02*
Y238506D01*
X184952Y238444D01*
G54D86*
G01X169700Y246375D02*
Y247099D01*
X172037Y249436D01*
X174100D01*
X174400Y249136D01*
G01D02*
Y246475D01*
X173600Y245675D01*
G01X190944Y210104D02*
X192921D01*
X193325Y209700D01*
G01X280555Y175635D02*
X278605D01*
X278155Y176085D01*
G01X283705Y175635D02*
X283813Y175527D01*
X285547D01*
X286105Y176085D01*
G01X307500Y256500D02*
X311899D01*
X314375Y258976D01*
Y260300D01*
G01Y268775D02*
X316659Y271059D01*
Y274089D01*
G01X311541Y266511D02*
Y260616D01*
X311225Y260300D01*
G54D77*
X316659Y266511D03*
X311541D03*
X316659Y274089D03*
X314100D03*
X311541D03*
G54D59*
X143118Y44803D03*
X194851D03*
G54D68*
X156220Y359838D03*
X158189D03*
X160157D03*
X162126D03*
X164094D03*
X166063D03*
Y368500D03*
X164094D03*
X162126D03*
X160157D03*
X158189D03*
X156220D03*
X168031Y359838D03*
X170000D03*
Y368500D03*
X168031D03*
G54D96*
G01X-35000Y56184D02*
Y77084D01*
X-33808Y78276D01*
X-24000D01*
X-22650Y79626D01*
Y81826D01*
X-24000Y83176D01*
X-38009D01*
X-42200Y87367D01*
Y93585D01*
X-38009Y97776D01*
X-24000D01*
X-22650Y99126D01*
Y101326D01*
X-24000Y102676D01*
X-38009D01*
X-42200Y106867D01*
Y113085D01*
X-38009Y117276D01*
X-24000D01*
X-22650Y118626D01*
Y120826D01*
X-24000Y122176D01*
X-38009D01*
X-42200Y126367D01*
Y132585D01*
X-38009Y136776D01*
X-24000D01*
X-22650Y138126D01*
Y140326D01*
X-24000Y141676D01*
X-38009D01*
X-42200Y145867D01*
Y152085D01*
X-38009Y156276D01*
X-24000D01*
X-22650Y157626D01*
Y159826D01*
X-24000Y161176D01*
X-38009D01*
X-42200Y165367D01*
Y171585D01*
X-38009Y175776D01*
X-24000D01*
X-22650Y177126D01*
Y179326D01*
X-23500Y180176D01*
Y182425D01*
X-22150Y183775D01*
X-20240D01*
X-17800Y181335D01*
Y175117D01*
X-21991Y170926D01*
X-36000D01*
X-37350Y169576D01*
Y167376D01*
X-36000Y166026D01*
X-21991D01*
X-17800Y161835D01*
Y155617D01*
X-21991Y151426D01*
X-36000D01*
X-37350Y150076D01*
Y147876D01*
X-36000Y146526D01*
X-21991D01*
X-17800Y142335D01*
Y136117D01*
X-21991Y131926D01*
X-36000D01*
X-37350Y130576D01*
Y128376D01*
X-36000Y127026D01*
X-21991D01*
X-17800Y122835D01*
Y116617D01*
X-21991Y112426D01*
X-36000D01*
X-37350Y111076D01*
Y108876D01*
X-36000Y107526D01*
X-21991D01*
X-17800Y103335D01*
Y97117D01*
X-21991Y92926D01*
X-36000D01*
X-37350Y91576D01*
Y89376D01*
X-36000Y88026D01*
X-21991D01*
X-17800Y83835D01*
Y77617D01*
X-21991Y73426D01*
X-24500D01*
X-25000Y72926D01*
Y56184D01*
G01X12500Y102000D02*
X10800Y103700D01*
Y108900D01*
X14451Y112551D01*
X16724D01*
X16725Y112550D01*
G01X22000Y111400D02*
X18775D01*
X16800Y109425D01*
Y109325D01*
G01X16725Y112550D02*
Y116200D01*
G01Y112550D02*
X16800Y112475D01*
G01X55100Y225500D02*
Y260200D01*
X53700Y261600D01*
Y304493D01*
X49980Y308213D01*
Y313520D01*
X44100Y319400D01*
X36899D01*
X35399Y320900D01*
X31400D01*
X26000Y315500D01*
X16500D01*
X16000Y316000D01*
Y320223D01*
X16100Y320323D01*
Y340500D01*
X11600Y345000D01*
Y402590D01*
X13210Y404200D01*
X14000D01*
G01X35300Y323900D02*
X31100D01*
X29500Y322300D01*
Y320500D01*
X26000Y317000D01*
X18000D01*
X17160Y317840D01*
Y340940D01*
X17000Y341100D01*
Y422000D01*
X23140Y428140D01*
Y428780D01*
X27160Y432800D01*
X32100D01*
G01X40000Y104200D02*
X33401D01*
X30960Y106641D01*
X27660D01*
G01X31890Y110400D02*
Y113080D01*
X35310Y116500D01*
X37500D01*
G01X22000Y111400D02*
X22359Y111759D01*
X27660D01*
G01X21000Y322575D02*
X23769D01*
X23810Y322534D01*
G01X29100Y327000D02*
Y331176D01*
X30462Y332538D01*
X37538D01*
X40500Y335500D01*
Y366500D01*
X40000Y367000D01*
X38450D01*
X36035Y366000D01*
X34500D01*
X33500Y367000D01*
Y370500D01*
X32000Y372000D01*
Y375800D01*
X29000Y378800D01*
Y391681D01*
X32700Y395381D01*
G01X21000Y319425D02*
X21405D01*
X24268Y320611D01*
X25303Y321303D01*
X26000Y322000D01*
Y324000D01*
X26500Y324500D01*
X28600D01*
X29100Y325000D01*
Y327000D01*
G01X23819Y339154D02*
Y343319D01*
X33000Y352500D01*
Y355500D01*
X37400Y359900D01*
G01X44525Y384000D02*
X42000D01*
X35600Y390400D01*
Y392400D01*
X34800Y393200D01*
Y403992D01*
X28200Y410592D01*
Y429700D01*
X29400Y430900D01*
G01X31500Y428500D02*
Y409499D01*
X40740Y400259D01*
Y388860D01*
X43770Y385830D01*
X45870D01*
X46925Y384775D01*
Y384000D01*
G01X40175Y29713D02*
X39124Y30764D01*
Y53983D01*
X55066Y69925D01*
X55500D01*
G01X63898Y24764D02*
X63893Y24769D01*
X62466D01*
X59912Y27323D01*
X42565D01*
X40175Y29713D01*
G01X35140Y106641D02*
X42360D01*
X42801Y106200D01*
X45325D01*
G01X40940Y112559D02*
Y112061D01*
X45325Y107676D01*
Y106200D01*
G01Y102300D02*
X42825D01*
X40925Y104200D01*
X40000D01*
G01X48000Y94425D02*
X45720D01*
X45001Y95144D01*
G01D02*
X43209Y96936D01*
Y99370D01*
X44286Y100447D01*
X49134D01*
X50841Y98740D01*
X53441D01*
G01X37500Y116500D02*
X51000D01*
X54500Y120000D01*
Y139800D01*
X62330Y147630D01*
Y174954D01*
X69316Y181940D01*
Y193054D01*
X66500Y195870D01*
Y202687D01*
X62960Y206227D01*
Y223840D01*
X57300Y229500D01*
Y256451D01*
X61661Y260812D01*
Y265299D01*
G01X35140Y111759D02*
X35864D01*
X38933Y114828D01*
X50672D01*
X51500Y114000D01*
G01X50105Y220480D02*
Y219605D01*
X48365Y217865D01*
X48028D01*
X48023Y217860D01*
G01D02*
X50140D01*
X54469Y213531D01*
X58823D01*
G01X44500Y215575D02*
X46000Y217075D01*
Y219525D01*
X46955Y220480D01*
G01X39800Y213800D02*
X41300D01*
X43075Y215575D01*
X44500D01*
G01X47800Y240843D02*
Y237800D01*
X35700Y225700D01*
Y218000D01*
G01X49700Y242900D02*
X47800Y241000D01*
Y240843D01*
G01X67386Y191935D02*
X61900Y197421D01*
Y223000D01*
X56160Y228740D01*
Y260640D01*
X54940Y261860D01*
Y304753D01*
X51040Y308653D01*
Y313960D01*
X41100Y323900D01*
X35300D01*
G01X46925Y344000D02*
X44500D01*
G01X46925Y348000D02*
X44500D01*
G01X46925Y360000D02*
X44525D01*
G01X50000Y352925D02*
X49575D01*
X47761Y354739D01*
Y357686D01*
X50075Y360000D01*
G01X46925Y368000D02*
Y367824D01*
X46355Y367254D01*
Y367241D01*
X44525Y365411D01*
Y364000D01*
G01X46925Y372000D02*
Y371724D01*
X44525Y369324D01*
Y368000D01*
G01X37300Y375000D02*
X35900Y376400D01*
Y378539D01*
X37116Y379755D01*
X40444D01*
X42099Y378100D01*
X46401D01*
X46925Y378624D01*
Y380000D01*
G01X36200Y368400D02*
X38355D01*
X40980Y371025D01*
G01X52765Y390200D02*
X52465Y389900D01*
X47425D01*
X46925Y389400D01*
Y388000D01*
G01Y376000D02*
X44525D01*
G01X48500Y405724D02*
X46624D01*
X45124Y404224D01*
X43124D01*
X42300Y403400D01*
Y392500D01*
X43150Y391650D01*
X44525D01*
G01X48500Y396276D02*
Y393155D01*
X47075Y391730D01*
G01X44341Y406480D02*
Y407801D01*
X48500Y411960D01*
Y417425D01*
G01X40400Y417225D02*
X44400D01*
G01X40400D02*
X38675D01*
X38100Y417800D01*
Y422400D01*
X54100Y438400D01*
Y448600D01*
G01X44400Y420375D02*
X45640D01*
X46100Y420835D01*
Y422800D01*
G01X40400Y420375D02*
Y422900D01*
X43900Y426400D01*
X45300D01*
G01D02*
Y427800D01*
X56500Y439000D01*
Y447600D01*
G01X78781Y64635D02*
X81885Y61531D01*
Y48919D01*
X84035Y46769D01*
X87619D01*
X89578Y44810D01*
Y37778D01*
X85900Y34100D01*
Y23600D01*
X82100Y19800D01*
X59800D01*
X54200Y25400D01*
G01X73898Y24764D02*
X61532Y37130D01*
Y54557D01*
X59549Y56540D01*
Y63000D01*
G01D02*
Y64041D01*
X60632Y65124D01*
X61214Y66528D01*
Y71534D01*
X62321Y72641D01*
Y80500D01*
X60746Y82075D01*
X59500D01*
G01X64500Y72075D02*
X62786Y70361D01*
Y66850D01*
X63086Y66550D01*
Y65762D01*
G01X59500Y69925D02*
X59408Y70017D01*
X55592D01*
X55500Y69925D01*
G01X52502Y80978D02*
Y83077D01*
X55425Y86000D01*
G01X59500Y82075D02*
X55500D01*
G01D02*
Y82925D01*
X58575Y86000D01*
G01X106000Y91900D02*
X101000Y86900D01*
Y82300D01*
X98300Y79600D01*
Y78800D01*
X97492Y77992D01*
X87308D01*
X85828Y79472D01*
X66467D01*
X62392Y83547D01*
Y87953D01*
X59085Y91260D01*
X58559D01*
G01X56000D02*
Y89950D01*
X57567Y88383D01*
X60051D01*
X61102Y87332D01*
Y83295D01*
X66015Y78382D01*
X82236D01*
X83500Y77118D01*
Y74958D01*
X82542Y74000D01*
X80500D01*
X78517Y72017D01*
Y64899D01*
X78781Y64635D01*
G01X70453Y222900D02*
Y219777D01*
X69310Y218634D01*
Y211618D01*
X77440Y203488D01*
Y171360D01*
X78272Y170528D01*
Y165618D01*
X75835Y159735D01*
X70610Y154510D01*
X67606D01*
X65185Y152089D01*
Y145943D01*
X57460Y138218D01*
Y116726D01*
X51284Y110550D01*
Y103312D01*
X50272Y102300D01*
X48475D01*
G01X75284Y180800D02*
X70100D01*
X63690Y174390D01*
Y146990D01*
X56100Y139400D01*
Y118600D01*
X51500Y114000D01*
G01X67486Y188977D02*
Y189245D01*
X64931Y191800D01*
X60100D01*
X57300Y194600D01*
Y204949D01*
X60670Y208319D01*
Y214970D01*
X60070Y215570D01*
X55590D01*
X55100Y216060D01*
Y225500D01*
G01X61216Y229725D02*
Y228095D01*
X64570Y224741D01*
Y219161D01*
X65380Y218351D01*
Y213120D01*
G01X59500Y240500D02*
Y242099D01*
X61201Y243800D01*
X62701D01*
X64220Y245319D01*
Y247701D01*
G01X61216Y232875D02*
X62500Y234159D01*
Y235800D01*
X61216Y237084D01*
Y238784D01*
X59500Y240500D01*
G01X66000Y274425D02*
X63175D01*
X61200Y276400D01*
G01X66000Y284925D02*
X67275D01*
X68000Y284200D01*
Y281200D01*
X67200Y280400D01*
X64200D01*
X63100Y279300D01*
Y278300D01*
X61200Y276400D01*
G01X52200Y327925D02*
X50480Y326205D01*
Y321620D01*
X53080Y319020D01*
Y317167D01*
X52600Y316687D01*
Y309300D01*
X56500Y305400D01*
Y297194D01*
X62794Y290900D01*
X72800D01*
X75300Y288400D01*
X79700D01*
X82300Y291000D01*
X91101D01*
X93860Y293759D01*
Y300360D01*
X94812Y301312D01*
G01X90923Y293520D02*
X90003Y292600D01*
X63301D01*
X60000Y295901D01*
Y308600D01*
X58334Y310266D01*
Y316266D01*
X56600Y318000D01*
G01X66000Y288075D02*
X58900D01*
G01X54660Y311660D02*
Y314160D01*
X55500Y315000D01*
G01D02*
X54660Y315840D01*
Y321260D01*
X55800Y322400D01*
X57290D01*
X62100Y327210D01*
Y329075D01*
X64100Y331075D01*
G01X60613Y312012D02*
X60617Y312008D01*
Y310769D01*
X61118Y310268D01*
X63768D01*
X65400Y311900D01*
G01X60000Y327925D02*
X59024D01*
X56600Y325501D01*
Y324300D01*
G01X60000Y331075D02*
X60976D01*
X63600Y333699D01*
Y338530D01*
X64850Y339780D01*
X66070D01*
G01X56100Y331075D02*
X58325Y333300D01*
X60299D01*
X62100Y335101D01*
Y339700D01*
X65400Y343000D01*
Y344200D01*
G01X52200Y331075D02*
X55125Y334000D01*
X56300D01*
X57960Y335660D01*
Y337140D01*
X54500Y340600D01*
Y341390D01*
G01X52820Y325200D02*
X55545Y327925D01*
X56100D01*
G01X72000D02*
Y325400D01*
X69200Y322600D01*
X67942D01*
X63342Y318000D01*
X60600D01*
G01X54500Y341390D02*
Y343300D01*
X55600Y344400D01*
Y345739D01*
X56351Y347551D01*
X62400Y353600D01*
X63334D01*
X65607Y355873D01*
G01X50075Y344000D02*
X52601D01*
X54530Y345929D01*
Y348200D01*
G01X50075Y368000D02*
X51100D01*
X52040Y367060D01*
Y367053D01*
X58093Y361000D01*
X62001D01*
X67853Y366852D01*
X70376D01*
X71906Y365322D01*
G01X54500Y355000D02*
X56400D01*
X59900Y358500D01*
X62600D01*
X64653Y360553D01*
X69301D01*
X70287Y361539D01*
Y363792D01*
X68757Y365322D01*
G01X50075Y348000D02*
X51150D01*
X54501Y351351D01*
Y354999D01*
X54500Y355000D01*
G01X50075Y360000D02*
X52075Y362000D01*
X54500D01*
X56700Y359800D01*
X62200D01*
X64573Y362173D01*
X68757D01*
G01X54530Y348200D02*
X57830Y351500D01*
X58400D01*
X60094Y353194D01*
Y355673D01*
X61914Y357493D01*
X67227D01*
X68757Y359023D01*
G01X56625Y372600D02*
Y371510D01*
X58035Y370100D01*
G01X59775Y372600D02*
X62075D01*
X63091Y371584D01*
X65607D01*
G01X56925Y367700D02*
X55754D01*
X55294Y368160D01*
Y369729D01*
G01X60075Y367700D02*
X64500D01*
X66501Y369701D01*
X72099D01*
X74051Y367749D01*
X75056Y365322D01*
G01X59775Y376300D02*
X62875Y373200D01*
X66201D01*
X67817Y371584D01*
X68757D01*
G01X50075Y372000D02*
X52500Y369575D01*
Y368499D01*
X57899Y363100D01*
X59600D01*
G01D02*
X62200D01*
X67000Y367900D01*
X71600D01*
X73500Y366000D01*
Y363767D01*
X71906Y362173D01*
G01X50075Y380000D02*
X51875Y381800D01*
X54800D01*
G01X65607Y374733D02*
X64167D01*
X61900Y377000D01*
Y379900D01*
X60000Y381800D01*
X54800D01*
G01X54600Y388000D02*
X50075D01*
G01X54600D02*
X57100D01*
X59300Y385800D01*
X63989D01*
X65607Y384182D01*
G01X68719Y381033D02*
X67152Y382600D01*
X62800D01*
X61924Y383476D01*
G01X50075Y384000D02*
X50875Y384800D01*
X60600D01*
X61924Y383476D01*
G01X81355Y381033D02*
X81123D01*
X78100Y384056D01*
Y389891D01*
X71252Y396739D01*
X67862D01*
X61000Y403601D01*
Y409600D01*
X58000Y412600D01*
G01X48500Y420575D02*
Y427199D01*
X50001Y428700D01*
X57903D01*
X59733Y426870D01*
X62455D01*
G01X56500Y420575D02*
X57275D01*
X59100Y422400D01*
X63100D01*
X65600Y424900D01*
Y427000D01*
X67800Y429200D01*
X73971D01*
G01X52500Y417425D02*
X48500D01*
G01X52500Y420575D02*
X54125D01*
X54500Y420200D01*
Y416100D01*
X53900Y415500D01*
X51330D01*
X50500Y414670D01*
Y412568D01*
X51868Y411200D01*
X56600D01*
X58000Y412600D01*
G01X60500Y417425D02*
X56500D01*
G01D02*
Y415400D01*
X54450Y413350D01*
X52330D01*
G01X60500Y420575D02*
X63225D01*
X64300Y419500D01*
Y412970D01*
X63715Y412385D01*
G01X62455Y426870D02*
X63970D01*
X68500Y431400D01*
Y433700D01*
X70870Y436070D01*
X78385D01*
X87320Y445005D01*
Y454112D01*
X90046Y456838D01*
Y459846D01*
X91909Y461709D01*
Y466378D01*
G01X68500Y72075D02*
X66549Y70124D01*
Y58951D01*
X70500Y55000D01*
Y49500D01*
X75709Y44291D01*
Y42244D01*
G01Y52244D02*
X70467Y57486D01*
Y70042D01*
X72500Y72075D01*
G01X64500Y68925D02*
X64949Y68476D01*
Y55679D01*
X65709Y54919D01*
Y52244D01*
G01X85709Y42244D02*
X80643Y47310D01*
Y56782D01*
X74552Y62873D01*
Y70897D01*
X75730Y72075D01*
X76500D01*
G01X72500Y68925D02*
Y66500D01*
G01X68500Y72075D02*
X72075Y75650D01*
Y76500D01*
G01X76500Y72075D02*
X78924Y74499D01*
X79475D01*
X80976Y76000D01*
X81075D01*
G01X71146Y186489D02*
X71455D01*
X75700Y190734D01*
Y200000D01*
X72800Y202900D01*
X70701D01*
X66080Y207521D01*
Y209290D01*
X67750Y210960D01*
Y219470D01*
X66700Y220520D01*
G01X65380Y213120D02*
X64520Y212260D01*
Y206874D01*
X69498Y201896D01*
X69497Y200003D01*
X71607Y197893D01*
Y189231D01*
X71370Y188994D01*
Y188993D01*
G01X89200Y138800D02*
X88100D01*
X87340Y139560D01*
Y142500D01*
X88690Y143850D01*
Y163710D01*
X78800Y173600D01*
Y204052D01*
X70670Y212182D01*
Y218070D01*
X72500Y219900D01*
Y224300D01*
X71100Y225700D01*
Y229741D01*
G01X66700Y220520D02*
Y225101D01*
X65216Y226585D01*
Y229725D01*
G01X64500Y240400D02*
Y243000D01*
X66780Y245280D01*
Y247701D01*
G01X65216Y232875D02*
Y234506D01*
X65500Y234790D01*
Y239400D01*
X64500Y240400D01*
G01X71100Y233575D02*
Y229741D01*
G01X80600Y254825D02*
X79725Y255700D01*
X77955D01*
X77010Y256645D01*
G01X66780Y265299D02*
Y269527D01*
X67560Y270307D01*
Y271985D01*
X70000Y274425D01*
G01X66000D02*
Y270954D01*
X64220Y269174D01*
Y265299D01*
G01X70000Y274425D02*
X70824D01*
X72300Y275901D01*
Y282500D01*
G01D02*
X70125Y284675D01*
Y287100D01*
G01X75960Y284049D02*
X74693Y285316D01*
Y285599D01*
X73275Y287017D01*
Y287100D01*
G01X71900Y310075D02*
X76079D01*
X77761Y308393D01*
G01X68000Y316425D02*
X65400Y313825D01*
Y311900D01*
G01X66065Y335220D02*
Y332957D01*
X64183Y331075D01*
X64100D01*
G01X68100Y327925D02*
Y325500D01*
X68500Y325100D01*
G01X76500Y327925D02*
X77776D01*
X78500Y327201D01*
Y324600D01*
X76900Y323000D01*
G01X76500Y331075D02*
X78000Y332575D01*
Y335700D01*
X78900Y336600D01*
G01X68000Y319575D02*
X73301D01*
G01X81700Y342600D02*
X78400D01*
X76800Y341000D01*
Y334500D01*
X74670Y332370D01*
Y324741D01*
X74900Y324511D01*
Y321174D01*
X73301Y319575D01*
G01X72000Y331075D02*
X72740Y331815D01*
Y332650D01*
X74500Y334410D01*
Y335700D01*
G01X68100Y331075D02*
X68575D01*
X72530Y335030D01*
Y338530D01*
X74000Y340000D01*
Y341500D01*
X78206Y345706D01*
Y349574D01*
G01X66070Y339780D02*
Y341000D01*
X71906Y346836D01*
Y349574D01*
G01X68757D02*
Y348589D01*
X65400Y345232D01*
Y344200D01*
G01X69215Y335220D02*
Y341785D01*
X73400Y345970D01*
Y346933D01*
X74422Y347955D01*
X75855D01*
X76676Y348776D01*
Y350208D01*
X77572Y351104D01*
X78804D01*
X79800Y352100D01*
Y353399D01*
X78945Y354254D01*
X78645D01*
X78206Y354693D01*
Y355873D01*
G01X74500Y335700D02*
Y339000D01*
X75100Y339600D01*
Y341200D01*
X79800Y345900D01*
Y348019D01*
X81355Y349574D01*
G01X70500Y403075D02*
X69175D01*
X67900Y401800D01*
Y400525D01*
G01X78500Y403075D02*
Y404285D01*
X77860Y404925D01*
Y408678D01*
G01X74500Y403075D02*
X71570Y406005D01*
Y409530D01*
X70450Y410650D01*
X68250D01*
X66319Y412581D01*
Y413492D01*
G01X70500Y399925D02*
X80125Y390300D01*
X81355D01*
G01X74500Y399925D02*
Y397269D01*
X79269Y392500D01*
X82983D01*
X83900Y391583D01*
Y385700D01*
G01X63715Y412385D02*
X65170Y410930D01*
Y400648D01*
X68218Y397600D01*
X71608D01*
X79025Y390183D01*
Y384348D01*
X80810Y382563D01*
X81989D01*
X82885Y381667D01*
Y380399D01*
X81989Y379503D01*
X79826D01*
X78206Y377883D01*
G01X77600Y431400D02*
X81500Y427500D01*
Y423500D01*
X79422Y421422D01*
Y410063D01*
X79690Y409416D01*
Y408978D01*
X80492Y407042D01*
Y397008D01*
X83200Y394300D01*
X84700D01*
X85900Y393100D01*
Y386885D01*
X87617Y385168D01*
Y384182D01*
G01X73971Y429200D02*
X77300D01*
X79600Y426900D01*
Y426400D01*
G01X72800Y437900D02*
X76520Y441620D01*
Y447620D01*
X84000Y455100D01*
Y455400D01*
X86890Y458290D01*
Y461529D01*
X87305Y461944D01*
Y465470D01*
X87185Y465590D01*
G01X90472Y24764D02*
X91500Y25792D01*
Y62881D01*
X93561Y64942D01*
Y67547D01*
X92517Y68591D01*
Y69908D01*
X90500Y71925D01*
G01X82500Y68925D02*
Y64740D01*
X84500Y62740D01*
Y60000D01*
X85709Y58791D01*
Y52244D01*
G01X84500Y66500D02*
Y70075D01*
X82500Y72075D01*
G01X86500D02*
X90350D01*
X90500Y71925D01*
G01X84016Y258230D02*
X80855D01*
X80600Y257975D01*
G01X88700Y318300D02*
Y311500D01*
X89700Y310500D01*
Y305568D01*
X86029Y301897D01*
G01X88700Y331075D02*
Y337123D01*
G01Y327925D02*
Y318300D01*
G01Y337123D02*
Y341352D01*
X87617Y342435D01*
Y349574D01*
G01X81355Y390300D02*
Y387332D01*
G01Y384182D02*
X83440D01*
X83900Y384642D01*
Y385700D01*
G01X86500Y403075D02*
X89487Y406062D01*
Y408435D01*
G01X84801Y409760D02*
X84500Y409459D01*
Y407500D01*
X82500Y405500D01*
Y403075D01*
G01X78500Y399925D02*
Y396000D01*
X79000Y395500D01*
G01X86500Y399925D02*
X88400Y398025D01*
Y396800D01*
X89495Y395705D01*
X90911D01*
X91206Y396000D01*
X93240D01*
X94200Y395040D01*
Y391000D01*
G01X87800Y410300D02*
X85370Y412730D01*
Y418750D01*
X87495Y420875D01*
X88800D01*
G01X92500Y408630D02*
X90800Y410330D01*
Y424300D01*
X88565Y426535D01*
G01X81552Y409660D02*
Y415977D01*
X83000Y417425D01*
Y422000D01*
X84000Y423000D01*
Y425500D01*
G01X94710Y433260D02*
X93381D01*
X92921Y433720D01*
Y437831D01*
X92870D01*
G01X93259Y424200D02*
Y421355D01*
X92809Y420905D01*
G01X96634Y465590D02*
Y457366D01*
X99480Y454520D01*
Y448960D01*
X98520Y448000D01*
X95798D01*
X86450Y438652D01*
Y435050D01*
X89500Y432000D01*
G01D02*
X86450Y428950D01*
Y424850D01*
X88800Y422500D01*
Y420875D01*
G01X94272Y465590D02*
Y456772D01*
X93000Y455500D01*
X90208D01*
X88380Y453672D01*
Y442789D01*
X81500Y435909D01*
Y429000D01*
X84000Y426500D01*
Y425500D01*
G01X79010Y445750D02*
Y447809D01*
X85600Y454399D01*
Y454599D01*
X88486Y457485D01*
Y460873D01*
X88500Y460887D01*
Y460900D01*
X89553Y461953D01*
X89547Y461959D01*
Y465590D01*
G01X98996Y466378D02*
Y461497D01*
X101040Y459453D01*
Y447460D01*
X103000Y445500D01*
Y442000D01*
X101500Y440500D01*
X92300D01*
X89700Y437900D01*
G01X95709Y42244D02*
Y42351D01*
X99900Y46542D01*
Y55511D01*
X102389Y58000D01*
X104000D01*
X105722Y59722D01*
G01D02*
X107896Y61896D01*
Y67008D01*
X101475Y73429D01*
X99354D01*
X98500Y72575D01*
G01D02*
X94500D01*
G01X106036Y78566D02*
X109434D01*
X111000Y77000D01*
G01X103580Y237400D02*
X105334Y239154D01*
Y244266D01*
X102500Y247100D01*
Y261708D01*
X106570Y271531D01*
Y274459D01*
X107641Y275530D01*
X109321D01*
X116791Y283000D01*
X127025D01*
G01X112325Y249900D02*
X111932Y250293D01*
X110040D01*
X106934Y247187D01*
Y235434D01*
X106200Y234700D01*
X102700D01*
X101400Y236000D01*
Y244000D01*
X99800Y245600D01*
Y266712D01*
X101983Y271983D01*
X107300Y277300D01*
X109167D01*
X117967Y286100D01*
X136600D01*
X140879Y281821D01*
X152839D01*
X160710Y273950D01*
X164350D01*
X165556Y275156D01*
X168656D01*
G01X119441Y269437D02*
Y265441D01*
X118500Y264500D01*
X116600D01*
X112700Y260600D01*
X108276D01*
X106800Y262076D01*
G01X105100Y309300D02*
X97112Y301312D01*
X94812D01*
G01X99026Y338368D02*
Y336868D01*
X102210Y333684D01*
X105509D01*
X105600Y333775D01*
G01X97066Y349574D02*
Y342834D01*
X98377Y341523D01*
G01X106025Y337700D02*
X104394D01*
X100571Y341523D01*
X98377D01*
G01X105950Y341649D02*
X103351D01*
X100253Y344747D01*
Y346387D01*
G01X100215Y349574D02*
X101800Y347989D01*
Y345701D01*
X103451Y344050D01*
X119370D01*
G01X100215Y387332D02*
Y390486D01*
X98500Y392201D01*
Y394800D01*
G01X94200Y391000D02*
X95500Y389700D01*
Y384900D01*
X94782Y384182D01*
X93916D01*
G01X94500Y403075D02*
X98500D01*
G01D02*
Y407400D01*
X98300Y407600D01*
G01X98500Y394800D02*
Y399925D01*
G01X108500Y408680D02*
X106779D01*
X102500Y404401D01*
Y403075D01*
G01X106550Y431630D02*
Y421550D01*
X105500Y420500D01*
Y418200D01*
G01X106550Y431630D02*
Y433551D01*
X113990Y440991D01*
Y458111D01*
X110807Y461294D01*
Y465590D01*
G01X106550Y431630D02*
X102430D01*
X100970Y430170D01*
Y424676D01*
X101000Y424646D01*
Y420825D01*
X96894D01*
X96814Y420905D01*
G01X94710Y433260D02*
X99361D01*
X110850Y444749D01*
Y456649D01*
X106083Y461416D01*
Y466378D01*
G01X108445Y465590D02*
Y461354D01*
X112430Y457369D01*
Y444122D01*
X93259Y424951D01*
Y424200D01*
G01X106700Y447730D02*
X105900Y448530D01*
Y452100D01*
X102600Y455400D01*
Y460100D01*
X101358Y461342D01*
Y465590D01*
G01X95770Y437920D02*
X101820D01*
X109360Y445460D01*
Y451650D01*
X104200Y456810D01*
Y461550D01*
X103721Y462029D01*
Y465590D01*
G01X115600Y117950D02*
X115450D01*
X115425Y117925D01*
X115126D01*
X112201Y115000D01*
X109851D01*
X109350Y115501D01*
G01X111600Y117950D02*
X111450D01*
X111425Y117925D01*
X109775D01*
X109200Y118500D01*
G01X125500Y117925D02*
X123100Y115525D01*
X120500D01*
G01X116475Y109300D02*
X120361D01*
X120724Y108937D01*
G01X109200Y128500D02*
X111925D01*
X112500Y129075D01*
G01X123500Y128075D02*
X119451D01*
X118990Y128536D01*
G01D02*
Y131580D01*
G01X138000Y244600D02*
X136069Y245400D01*
X125365D01*
X123635Y247130D01*
X122117D01*
X119017Y244030D01*
X117081D01*
X116010Y242959D01*
Y236390D01*
X117598Y234802D01*
X119853Y229359D01*
Y228056D01*
X125300Y214906D01*
Y212600D01*
X122907Y210207D01*
X121300Y206327D01*
Y179917D01*
X108270Y166887D01*
Y138630D01*
G01X113000Y160700D02*
X110700Y163000D01*
Y167110D01*
X123870Y180280D01*
Y184459D01*
X125811Y186400D01*
X133433D01*
G01X153100Y234800D02*
X152500Y234200D01*
X144880D01*
X140595Y238485D01*
X133895D01*
X131410Y240970D01*
X125970D01*
X125380Y240380D01*
X119660D01*
X117840Y242200D01*
G01X126225Y249700D02*
X121437D01*
X119689Y247952D01*
X112379D01*
X109299Y244872D01*
Y233535D01*
X112044Y230790D01*
X116143D01*
G01X119441Y261563D02*
Y260142D01*
X115475Y256176D01*
Y254900D01*
G01D02*
Y249900D01*
G01X113157Y270929D02*
X113731Y271503D01*
X118463D01*
X119441Y270525D01*
Y269437D01*
G01X161635Y276500D02*
X155994Y282141D01*
Y284305D01*
X153844Y286455D01*
X142045D01*
X140400Y288100D01*
X118796D01*
X113246Y293650D01*
Y294162D01*
X112032Y295376D01*
X111520D01*
X110565Y296331D01*
G01X109175Y337700D02*
X111640Y335235D01*
X115535D01*
G01X115600Y337900D02*
Y339100D01*
X114060Y340640D01*
G01X109100Y341649D02*
X113051D01*
X114060Y340640D01*
G01X119370Y344050D02*
Y348705D01*
G01X121200Y359200D02*
X122200Y358200D01*
Y356400D01*
G01X119370Y351855D02*
Y353570D01*
X122200Y356400D01*
G01X117594Y362623D02*
Y358519D01*
X117575Y358500D01*
G01D02*
X117700D01*
X119100Y359900D01*
Y360500D01*
X120200Y361600D01*
G01X117675Y366600D02*
X119905Y368830D01*
X121630D01*
X127300Y374500D01*
X129776D01*
G01X114525Y366600D02*
X111950Y369175D01*
Y371200D01*
G01X114444Y362623D02*
X114113Y362954D01*
X112644D01*
X111460Y361770D01*
G01X117900Y425980D02*
Y422006D01*
X117400Y421506D01*
Y419875D01*
G01X121700Y424005D02*
X120000Y422305D01*
Y417000D01*
X123250Y413750D01*
Y410250D01*
X126500Y407000D01*
Y405000D01*
X126000Y404500D01*
Y402575D01*
G01X122498Y419675D02*
Y416709D01*
X124810Y414397D01*
Y411189D01*
X130000Y405999D01*
Y402575D01*
G01X119500Y433600D02*
X117900Y432000D01*
Y425980D01*
G01X128500Y426070D02*
Y429199D01*
X126513Y431186D01*
X122060D01*
X121340Y431906D01*
Y434850D01*
X119500Y436690D01*
Y459800D01*
X117894Y461406D01*
Y465590D01*
G01X113169Y466378D02*
Y461230D01*
X115550Y458849D01*
Y438750D01*
X111510Y434710D01*
G01X123170Y433200D02*
Y437430D01*
X121100Y439500D01*
Y460800D01*
X120256Y461644D01*
Y466378D01*
G01X139725Y78700D02*
Y74724D01*
X138600Y73599D01*
Y69000D01*
X140300Y67300D01*
Y54800D01*
X134730Y49230D01*
Y39545D01*
X146200Y28075D01*
G01X132400Y88325D02*
Y84375D01*
X132325Y84300D01*
G01X133000Y78900D02*
X131100D01*
X130209Y79791D01*
X123740D01*
G01X133000Y78900D02*
X133400Y79300D01*
Y82695D01*
X132699Y83396D01*
X132325Y84300D01*
G01X132400Y91475D02*
X129500D01*
G01Y116425D02*
X127721D01*
X123325Y112029D01*
Y111000D01*
G01X139500Y140925D02*
Y139000D01*
X135500Y135000D01*
G01Y138000D02*
Y140925D01*
G01X133500Y146800D02*
X135500Y144800D01*
Y144075D01*
G01X133690Y158100D02*
Y159090D01*
X140360Y165760D01*
X147453D01*
X149293Y167600D01*
X154807D01*
X156707Y169500D01*
X163425D01*
G01Y165500D02*
X162885Y166040D01*
X149940D01*
X148100Y164200D01*
X142290D01*
X136190Y158100D01*
G01X133433Y186400D02*
X135700D01*
X141290Y180810D01*
Y178001D01*
X147991Y171300D01*
X150200D01*
X151800Y172900D01*
X159661D01*
X163646Y176885D01*
G01X124338Y204742D02*
X126688D01*
X134116Y197314D01*
Y195691D01*
X134025Y195600D01*
G01X125700Y183700D02*
X128900D01*
G01X163625Y173200D02*
X162168D01*
X160308Y171340D01*
X156340D01*
X154160Y169160D01*
X147924D01*
X139730Y177354D01*
Y180163D01*
X136193Y183700D01*
X128900D01*
G01X137175Y195600D02*
X137779Y196204D01*
X141694D01*
G01X124559Y261563D02*
Y255500D01*
G01X129375Y249700D02*
X124559Y254516D01*
Y255500D01*
G01X131941Y261563D02*
Y259958D01*
X136331Y255568D01*
X137059D01*
G01X135625Y250700D02*
Y252126D01*
X137059Y253560D01*
Y255568D01*
G01Y269437D02*
Y267859D01*
X135700Y266500D01*
X130900D01*
X125776Y271624D01*
X125124D01*
X124559Y271059D01*
Y269437D01*
G01X137196Y274491D02*
Y274139D01*
X137320Y274015D01*
Y269698D01*
X137059Y269437D01*
G01X132420Y273811D02*
Y273790D01*
X131941Y273311D01*
Y269437D01*
G01X137059Y261563D02*
Y264319D01*
X139200Y266460D01*
Y280799D01*
X136999Y283000D01*
X134788D01*
G01X130175D02*
X134788D01*
G01X127425Y361500D02*
Y357500D01*
G01D02*
Y353500D01*
G01D02*
Y351925D01*
X124300Y348800D01*
G01X126610Y387024D02*
Y390010D01*
X127100Y390500D01*
X128000D01*
X129400Y391900D01*
Y394300D01*
X127950Y395750D01*
G01X134090Y377576D02*
X137000Y380486D01*
Y395500D01*
X132700Y399800D01*
Y402700D01*
G01X134400Y394600D02*
X130350Y390550D01*
Y387024D01*
G01X127950Y395750D02*
X126000Y397700D01*
Y399425D01*
G01X130000D02*
X134400Y395025D01*
Y394600D01*
G01X128500Y417925D02*
X127140Y416565D01*
Y412244D01*
X129134Y410250D01*
X129135D01*
G01X128500Y421075D02*
Y426070D01*
G01X146673Y465590D02*
Y461673D01*
X145600Y460600D01*
Y455413D01*
X141480Y451293D01*
Y445186D01*
X137780Y441486D01*
Y430370D01*
X134805Y427395D01*
G01D02*
X133572Y426162D01*
Y423935D01*
G01X190500Y18000D02*
X180700Y8200D01*
X152300D01*
X150900Y9600D01*
Y12657D01*
G01X155500Y28075D02*
X146200D01*
G01X151000Y24925D02*
X155500D01*
G01X147947Y19743D02*
Y21872D01*
X151000Y24925D01*
G01X141100Y86500D02*
X142330Y85270D01*
X147030D01*
X148800Y83500D01*
Y71800D01*
X146270Y69270D01*
Y53231D01*
X163501Y36000D01*
X165500D01*
X169500Y32000D01*
G01X139725Y78700D02*
Y84960D01*
X138580Y86105D01*
Y89380D01*
X140500Y91300D01*
X142400D01*
G01X147600Y117000D02*
X147587Y117013D01*
Y119813D01*
G01D02*
X148813D01*
X151512Y122512D01*
Y131188D01*
X155327Y135003D01*
X156173Y137045D01*
X157249Y138121D01*
Y143540D01*
X160625Y146916D01*
Y147000D01*
G01X151800Y116500D02*
X152709D01*
X155325Y119116D01*
Y119200D01*
G01X178346Y159748D02*
X177768D01*
X176220Y158200D01*
X174240D01*
X173620Y157580D01*
Y155629D01*
X173060Y155069D01*
X170959D01*
X170390Y154500D01*
Y152590D01*
X168550Y150750D01*
Y148850D01*
X159400Y139700D01*
Y138200D01*
X156900Y135700D01*
Y133200D01*
X153900Y130200D01*
Y120900D01*
X152200Y119200D01*
X150600D01*
X149800Y118400D01*
Y114600D01*
X152800Y111600D01*
G01X138458Y146458D02*
X138542D01*
X139500Y145500D01*
Y144075D01*
G01X148967Y173433D02*
Y176066D01*
X150619Y177718D01*
Y178646D01*
G01X153445Y175720D02*
X151254D01*
X148967Y173433D01*
G01X151275Y182110D02*
Y183703D01*
X150005Y184973D01*
G01X155633Y189082D02*
X154006D01*
X153488Y189600D01*
X151599D01*
X150637Y188638D01*
Y187376D01*
X150005Y186744D01*
Y184973D01*
G01X155633Y192582D02*
X154006D01*
X153988Y192600D01*
X150659D01*
G01X149100Y189963D02*
X149713D01*
X150637Y190887D01*
Y192622D01*
X150659Y192600D01*
G01X141694Y196204D02*
X142768Y195130D01*
X144280D01*
G01X155150Y232300D02*
X153700D01*
X152400Y231000D01*
X150430D01*
G01X142085Y230549D02*
X142536Y231000D01*
X150430D01*
G01X154516Y242629D02*
X152885D01*
X152735Y242479D01*
X151566D01*
X150745Y241658D01*
X148978D01*
X147202Y243434D01*
Y244142D01*
X148000Y244940D01*
Y266190D01*
X147150Y267040D01*
Y273000D01*
G01X163457Y238479D02*
Y243263D01*
X160880Y245840D01*
X151914D01*
X149862Y243788D01*
G01X152000Y255875D02*
Y259925D01*
G01X181495Y229002D02*
Y230905D01*
X178209Y234191D01*
X173620Y237254D01*
X171617Y238083D01*
X167400Y242300D01*
Y244100D01*
X164250Y247250D01*
X153250D01*
X152300Y248200D01*
G01D02*
X152000Y248500D01*
Y252725D01*
G01X168710Y272256D02*
X168387Y271933D01*
X159983D01*
X151996Y279920D01*
X145270D01*
X143660Y278310D01*
Y268540D01*
X145900Y266300D01*
Y261300D01*
X143120Y258520D01*
Y255045D01*
X138775Y250700D01*
G01X169425Y267000D02*
X165901Y270524D01*
X154624D01*
X149600Y265500D01*
Y261000D01*
X150675Y259925D01*
X152000D01*
G01X147150Y273000D02*
Y274850D01*
X150240Y277940D01*
G01X158459Y340898D02*
X153273Y335712D01*
X149090Y325613D01*
Y321170D01*
X151276Y318984D01*
X156980Y305214D01*
X160850Y301344D01*
G01X151695Y357900D02*
X151700D01*
X154801Y361001D01*
X155599D01*
X156220Y360380D01*
Y359838D01*
G01X149000Y383070D02*
X150200Y381870D01*
Y376600D01*
X153400Y373400D01*
X153500D01*
G01X143205Y378760D02*
Y373198D01*
X145703Y370700D01*
G01X143205Y382760D02*
X141860D01*
X141200Y382100D01*
Y374510D01*
X139200Y372510D01*
G01X156220Y368500D02*
Y367860D01*
X155760Y367400D01*
X152060D01*
X150210Y369250D01*
G01D02*
X146355Y373105D01*
Y378760D01*
G01Y382760D02*
X148490Y380625D01*
Y374259D01*
G01D02*
X152149Y370600D01*
X157101D01*
X158189Y369512D01*
Y368500D01*
G01X145675Y392000D02*
X143725Y390050D01*
X140950D01*
G01D02*
X139400Y391600D01*
Y392460D01*
G01X153330Y391710D02*
X149115D01*
X148825Y392000D01*
G01Y397500D02*
Y401750D01*
G01X151265Y399500D02*
X151200Y399565D01*
Y401290D01*
X150740Y401750D01*
X148825D01*
G01X154110Y404090D02*
X153300Y403280D01*
Y398779D01*
X152021Y397500D01*
X148825D01*
G01X142511Y393690D02*
X144790D01*
X146400Y395300D01*
X153372D01*
X154638Y396566D01*
G01X151420Y432880D02*
X150100Y431560D01*
Y420425D01*
X150000Y420325D01*
G01X148060Y423500D02*
Y420941D01*
X148676Y420325D01*
X150000D01*
G01X143000Y414600D02*
X142900D01*
X142000Y415500D01*
Y417175D01*
G01X140600Y412300D02*
X143290D01*
X144830Y413840D01*
Y415470D01*
X143870Y416430D01*
Y419605D01*
X144590Y420325D01*
X146000D01*
G01D02*
X143503Y422822D01*
Y427403D01*
X146000Y429900D01*
G01X138000Y420325D02*
X142000D01*
G01X141185Y426899D02*
Y423510D01*
X138000Y420325D01*
G01X156122Y466378D02*
X156128Y466372D01*
Y457327D01*
X147800Y448999D01*
Y443450D01*
X151420Y439830D01*
Y432880D01*
G01X146000Y429900D02*
Y449201D01*
X153760Y456961D01*
Y465590D01*
G01X141185Y426899D02*
Y427686D01*
X143820Y430321D01*
Y442920D01*
X144600Y443700D01*
Y449999D01*
X151398Y456797D01*
Y465590D01*
G01X138987Y423935D02*
Y428527D01*
X140820Y430360D01*
Y433030D01*
G01D02*
Y442319D01*
X143040Y444539D01*
Y450646D01*
X147170Y454776D01*
Y459920D01*
X149035Y461785D01*
Y466378D01*
G01X153800Y420375D02*
X154030Y420605D01*
Y423859D01*
X154000Y423889D01*
Y424188D01*
X153971Y424217D01*
Y449129D01*
X153170Y449930D01*
X151398D01*
G01X144311Y465590D02*
Y461561D01*
X143950Y461200D01*
Y456700D01*
X138750Y451500D01*
G01X141949Y466378D02*
Y457699D01*
X138750Y454500D01*
G01X153853Y12657D02*
X158700D01*
X158732Y12625D01*
G01D02*
X163400D01*
G01D02*
X163924D01*
X166399Y15100D01*
X173893D01*
X174353Y14640D01*
Y12657D01*
G01X158952Y20203D02*
X163796D01*
X166812Y17187D01*
X169687D01*
X172243Y19743D01*
X174353D01*
G01X153853D02*
X158492D01*
X158952Y20203D01*
G01X165000Y24500D02*
X165075Y24425D01*
X169500D01*
G01X168447Y19743D02*
Y21540D01*
X167987Y22000D01*
X165500D01*
X165000Y22500D01*
Y24500D01*
G01X162419Y131032D02*
X162700Y130751D01*
Y128633D01*
X164560Y126773D01*
Y118040D01*
X164500Y117980D01*
Y107450D01*
X163610Y106560D01*
Y103900D01*
X165260Y102250D01*
X169700D01*
G01X162657Y117297D02*
Y119751D01*
G01X190944Y169197D02*
X189400Y167653D01*
Y165420D01*
X188419Y164439D01*
X187141D01*
X186235Y163533D01*
Y162051D01*
X185504Y161320D01*
X184022D01*
X183084Y160382D01*
Y159117D01*
X182181Y158214D01*
X180514D01*
X179900Y157600D01*
Y155800D01*
X178800Y154700D01*
Y154200D01*
X176200Y151600D01*
X173911D01*
X161800Y139489D01*
Y135210D01*
X158408Y131818D01*
Y125093D01*
X160800Y122701D01*
Y119894D01*
X160106Y119200D01*
X158475D01*
G01X166733Y128700D02*
X168664Y130631D01*
Y134343D01*
X168213Y134794D01*
X166717D01*
G01X166733Y128700D02*
Y122901D01*
G01X162657D02*
Y126087D01*
X159968Y128776D01*
Y131170D01*
X164071Y135273D01*
Y138772D01*
X165899Y140600D01*
X168100D01*
X170300Y142800D01*
Y144500D01*
X172100Y146300D01*
G01X175400Y149000D02*
X174400Y148000D01*
Y145870D01*
X172916Y144386D01*
X171946Y142045D01*
X169267Y139366D01*
X167342Y138568D01*
X166717Y137944D01*
G01X167800Y153400D02*
X166000Y151600D01*
X163500D01*
X162400Y150500D01*
X161900D01*
G01X165690Y149622D02*
X163775Y147707D01*
Y147000D01*
G01Y161150D02*
X163472Y160847D01*
X159328D01*
G01X166925Y161150D02*
X167275Y161500D01*
X170085D01*
X171477Y162892D01*
X171507D01*
G01X164646Y157290D02*
X163736Y158200D01*
X162200D01*
G01X159900Y155600D02*
Y155100D01*
X161600Y153400D01*
X164650D01*
G01X181495Y172347D02*
X180600D01*
X178980Y170727D01*
X177712D01*
X175448Y168463D01*
X171309Y166748D01*
X167823D01*
X166575Y165500D01*
G01X171600Y178000D02*
X168893Y177462D01*
X167373D01*
X166796Y176885D01*
G01X166575Y169500D02*
X168570D01*
X171677Y172607D01*
G01X171443Y183557D02*
X171389Y183502D01*
X169528Y183129D01*
X166927Y182050D01*
X166796Y181735D01*
G01X158780Y181573D02*
X161075D01*
X161237Y181735D01*
G01D02*
X163646D01*
G01X178346Y175496D02*
X169071D01*
X166775Y173200D01*
G01X184645Y181795D02*
X183025Y183415D01*
X176578D01*
X173693Y186300D01*
X170700D01*
X169025Y184625D01*
X166737Y183677D01*
X160688D01*
X158783Y185582D01*
G01X166796Y190725D02*
Y191604D01*
X165818Y192582D01*
X158783D01*
G01X166796Y190725D02*
X167323Y190198D01*
X170798D01*
X172806Y192206D01*
Y193434D01*
X174372Y195000D01*
X176000D01*
X176800Y194200D01*
G01X166796Y185952D02*
Y187266D01*
X165962Y188100D01*
X159783D01*
X158801Y189082D01*
X158783D01*
G01X166796Y185952D02*
X168060D01*
X170008Y187900D01*
X175800D01*
X177164Y186536D01*
X178965D01*
X179892Y185609D01*
X181495Y184945D01*
G01X157525Y228732D02*
X155894D01*
X155150Y229476D01*
Y232300D01*
G01X163500Y229184D02*
X161159D01*
X160707Y228732D01*
X160675D01*
G01X166607Y238479D02*
Y238395D01*
X168024Y236978D01*
Y236692D01*
X168716Y236000D01*
X171500D01*
X172500Y235000D01*
Y233700D01*
X173337Y232863D01*
X176144D01*
G01X159930Y239185D02*
X158015D01*
X157200Y240000D01*
G01X157666Y242629D02*
Y240466D01*
X157200Y240000D01*
G01X156970Y255000D02*
Y252593D01*
X156963Y252586D01*
G01X165013D02*
Y254986D01*
G01X160973Y252586D02*
Y254986D01*
G01X160590Y263300D02*
X160700D01*
X160765Y263235D01*
Y260538D01*
G01X156970Y263250D02*
Y260825D01*
X156695Y260550D01*
G01X164800Y263300D02*
X164900Y263200D01*
Y260635D01*
X164801Y260536D01*
G01X160300Y281848D02*
X167359D01*
G01X161635Y276500D02*
X164300D01*
X165800Y278000D01*
X170080D01*
X170540Y277540D01*
Y270440D01*
X169425Y269325D01*
Y267000D01*
G01X171215Y300900D02*
X171307Y300808D01*
Y299186D01*
X171215Y299094D01*
Y297015D01*
X170400Y296200D01*
X167260D01*
X166300Y297160D01*
Y310600D01*
X164500Y312400D01*
Y314800D01*
G01X202440Y333420D02*
X186809D01*
X183379Y329990D01*
X177985D01*
X169795Y321800D01*
X168101D01*
X166200Y319899D01*
Y316990D01*
X167254Y314446D01*
X173294Y308406D01*
X181179D01*
G01X187570Y337590D02*
X184240D01*
X181800Y335150D01*
X176500D01*
X172700Y331350D01*
X169587D01*
X166077Y327840D01*
Y327640D01*
G01X156752Y326128D02*
Y330164D01*
G01D02*
Y334052D01*
X159140Y336440D01*
X162077D01*
G01X155000Y321100D02*
X156400Y322500D01*
Y325776D01*
X156752Y326128D01*
G01X158467Y344067D02*
X159394Y343140D01*
X161749D01*
X163038Y343674D01*
X164459Y345095D01*
X178595D01*
X184932Y351432D01*
X189500Y362461D01*
Y368900D01*
G01X154500Y387350D02*
Y384639D01*
X156649Y379451D01*
X158169Y377931D01*
X160156Y373134D01*
X162126Y371164D01*
Y368500D01*
G01X153500Y373400D02*
X156300D01*
X160157Y369543D01*
Y368500D01*
G01X189500Y368900D02*
X190000Y369400D01*
Y384999D01*
X185699Y389300D01*
X170689D01*
X165501Y391448D01*
X161296D01*
G01Y394007D02*
X155627D01*
X153330Y391710D01*
G01X161296Y406803D02*
X156803D01*
X155543Y405543D01*
Y405523D01*
X154110Y404090D01*
G01X161296Y396566D02*
X154638D01*
G01X161296Y399125D02*
X165315D01*
X177201Y411011D01*
X188225D01*
X189917Y412703D01*
X193843D01*
X194600Y413460D01*
Y419660D01*
G01X161296Y401685D02*
X163885D01*
X174271Y412071D01*
X187785D01*
X190564Y414850D01*
X192470D01*
G01X161296Y404244D02*
X164944D01*
X173831Y413131D01*
X187345D01*
X188230Y414016D01*
Y417654D01*
X188239D01*
G01X153079Y412000D02*
X155860D01*
X156560Y411300D01*
X163200D01*
X165300Y413400D01*
Y415800D01*
X160725Y420375D01*
X157600D01*
G01D02*
Y422599D01*
X161300Y426299D01*
Y436300D01*
X163200Y438200D01*
Y444688D01*
X162494Y448230D01*
X160262Y453621D01*
X158484Y456946D01*
Y465590D01*
G01X167008Y430718D02*
X167980Y431690D01*
Y443228D01*
X164400Y451872D01*
Y458069D01*
X165571Y459240D01*
Y465590D01*
G01X165500Y433100D02*
Y445051D01*
X162600Y452053D01*
Y458900D01*
X163209Y459509D01*
Y466378D01*
G01X167933Y465590D02*
Y459384D01*
X166000Y457451D01*
Y452185D01*
X172058Y437563D01*
X172060Y433990D01*
Y433100D01*
G01X174353Y19743D02*
X177432D01*
X179400Y17775D01*
G01X171400Y12657D02*
Y11060D01*
X171860Y10600D01*
X179600D01*
X184500Y15500D01*
G01X169500Y27575D02*
Y32000D01*
G01X168985Y58583D02*
Y71000D01*
G01X190500Y18000D02*
X206200Y33700D01*
Y48048D01*
X187748Y66500D01*
X185400D01*
X178200Y73700D01*
Y76145D01*
G01X175700Y76245D02*
Y73088D01*
X184488Y64300D01*
X187034D01*
X204000Y47334D01*
Y35000D01*
X184500Y15500D01*
G01X173000Y74925D02*
X169000D01*
G01X168985Y71000D02*
Y74910D01*
X169000Y74925D01*
G01X178355Y83710D02*
X175910D01*
X175000Y82800D01*
Y80075D01*
X173000Y78075D01*
G01X176300Y98700D02*
Y98500D01*
X178000Y96800D01*
Y89740D01*
X178460Y89280D01*
X184220D01*
X185200Y88300D01*
Y83800D01*
X183800Y82400D01*
X181900D01*
X180590Y83710D01*
X178355D01*
G01X173000Y78075D02*
X189025D01*
X195230Y71870D01*
Y61970D01*
X206500Y50700D01*
X223800D01*
G01X185470Y93375D02*
X181960D01*
G01X182954Y134794D02*
X184364D01*
X184870Y134288D01*
Y129490D01*
X184410Y129030D01*
X182172D01*
X182108Y129094D01*
G01X170737Y134794D02*
X172145D01*
X172595Y134344D01*
Y130196D01*
X170867Y128468D01*
Y128211D01*
G01D02*
Y126779D01*
X170738Y126650D01*
Y122901D01*
G01X178761D02*
X179470Y123610D01*
Y125799D01*
X178290Y126979D01*
Y128824D01*
G01X178816Y134794D02*
X180114Y133496D01*
Y130645D01*
X178293Y128824D01*
X178290D01*
G01X174741Y122901D02*
X174658D01*
X172810Y124749D01*
Y126985D01*
X174553Y128728D01*
G01X174740Y134794D02*
X176003D01*
X176454Y134343D01*
Y130629D01*
X174553Y128728D01*
G01X182954Y137944D02*
X182170Y138728D01*
Y141259D01*
X184583Y143672D01*
X187172D01*
G01X175400Y149000D02*
X179965Y153565D01*
Y154083D01*
X180951Y155069D01*
X182268D01*
X183115Y155916D01*
Y157233D01*
X184011Y158129D01*
X185328D01*
X186264Y159065D01*
Y160382D01*
X187160Y161278D01*
X188672D01*
X189363Y161969D01*
Y163507D01*
X190304Y164448D01*
X194509D01*
X196447Y165251D01*
X197243Y166047D01*
G01X194094Y162898D02*
X193108D01*
X191543Y161333D01*
X190021D01*
X189392Y160704D01*
Y158492D01*
X189029Y158129D01*
X187160D01*
X186264Y157233D01*
Y155964D01*
X185279Y154979D01*
X184011D01*
X183115Y154083D01*
Y152515D01*
X180700Y150100D01*
X179799D01*
X176900Y147201D01*
Y145154D01*
X175450Y143704D01*
G01D02*
X174263Y142517D01*
X173522Y140729D01*
X170737Y137944D01*
G01X178816D02*
Y138509D01*
X179260Y138953D01*
Y138964D01*
X179390Y139094D01*
Y141291D01*
X186499Y148400D01*
X189300D01*
G01X197243Y162898D02*
X196999D01*
X195401Y161300D01*
X193293D01*
X192564Y160571D01*
Y156350D01*
X189324Y153110D01*
Y151696D01*
X187588Y149960D01*
X184660D01*
X181752Y147052D01*
G01X174740Y137944D02*
X176044D01*
X177700Y139600D01*
Y139611D01*
X177830Y139741D01*
Y143130D01*
X181752Y147052D01*
G01X171507Y162892D02*
X174662Y166047D01*
X181495D01*
G01X167796Y157290D02*
X169714Y159208D01*
X171808D01*
X177100Y164500D01*
X182200D01*
X183112Y165412D01*
X184645Y166047D01*
G01X181495Y162898D02*
X179930Y161333D01*
Y158920D01*
X179210Y158200D01*
X177690D01*
X176750Y157260D01*
Y155540D01*
X176210Y155000D01*
X174630D01*
X172890Y153260D01*
G01X171600Y178000D02*
X171752Y178227D01*
X173624Y178600D01*
X175263D01*
X175309Y178646D01*
X181495D01*
G01X171677Y172607D02*
X173192Y173619D01*
X174767Y173933D01*
X178956D01*
X180519Y175496D01*
X181495D01*
G01X171443Y183557D02*
X174042D01*
X175804Y181795D01*
X181495D01*
G01X176800Y194200D02*
Y190400D01*
X177575Y189625D01*
X178980D01*
X179876Y188729D01*
Y187550D01*
X180861Y186565D01*
X183025D01*
X184645Y184945D01*
G01X177300Y216725D02*
X175832D01*
X174757Y217800D01*
X174600D01*
G01X173800Y225400D02*
Y223600D01*
X177300Y220100D01*
Y219875D01*
G01X194094Y222703D02*
X189501Y227296D01*
Y230722D01*
X181802Y238421D01*
Y238444D01*
G01X187794Y225852D02*
Y226705D01*
X186175Y228324D01*
Y229636D01*
X185279Y230532D01*
X183967D01*
X179607Y234892D01*
X175196Y237838D01*
X175195Y237840D01*
X174175Y238520D01*
X172085Y239915D01*
X169700Y242300D01*
Y243225D01*
G01X187794Y229002D02*
X186263Y232697D01*
X184832Y234128D01*
X181144Y235656D01*
X179676Y237124D01*
X177500Y242375D01*
Y242525D01*
G01X187794Y222703D02*
X186175Y224322D01*
Y226486D01*
X185189Y227472D01*
X180861D01*
X179965Y228368D01*
Y230635D01*
X177737Y232863D01*
X176144D01*
G01X177500Y245675D02*
X179071Y249467D01*
X179754Y250150D01*
G01D02*
Y255058D01*
X179846Y255150D01*
G01X173600Y242525D02*
X177500D01*
G01X174292Y263300D02*
Y263204D01*
X174392Y263104D01*
Y260806D01*
X173992Y260406D01*
G01X171592Y263312D02*
X169934Y261654D01*
Y260408D01*
G01X175713Y295099D02*
X178294D01*
X179364Y294029D01*
Y290331D01*
X179824Y289871D01*
X181863D01*
G01D02*
X185497D01*
X186798Y291172D01*
G01X181179Y305847D02*
X178697D01*
X174365Y301515D01*
Y300900D01*
G01D02*
X178700D01*
X178900Y301100D01*
G01X194600Y313300D02*
X193393Y312093D01*
X193293D01*
X190000Y308800D01*
Y306760D01*
X186540Y303300D01*
X181100D01*
X178900Y301100D01*
G01X185125Y300300D02*
X182232Y297407D01*
Y296424D01*
G01X176563Y310917D02*
X176611Y310965D01*
X181179D01*
G01Y313524D02*
X177058D01*
X176533Y314049D01*
G01X187180Y329590D02*
X186120Y328530D01*
X178590D01*
X170190Y320130D01*
X169230D01*
X168171Y319071D01*
Y316629D01*
X170400Y314400D01*
X172696D01*
X174696Y316400D01*
X177299D01*
X177615Y316084D01*
X181179D01*
G01X170800Y317600D02*
X174900Y321700D01*
X177002D01*
X177500Y321202D01*
X181179D01*
G01X216250Y328130D02*
X215580Y328800D01*
X204200D01*
X201304Y325904D01*
X199996D01*
X197282Y328618D01*
X196630D01*
X196170Y328158D01*
Y327434D01*
X200125Y323479D01*
Y322545D01*
X199665Y322085D01*
X198731D01*
X195416Y325400D01*
X194600D01*
X194022Y324822D01*
Y324006D01*
X197206Y320822D01*
Y320006D01*
X194943Y317743D01*
X194064D01*
X192404Y319403D01*
Y324160D01*
X191944Y324620D01*
X190894D01*
X190434Y324160D01*
Y316846D01*
X191011Y316269D01*
X191300D01*
X191800Y315769D01*
Y314799D01*
X191300Y314299D01*
X191011D01*
X190434Y313722D01*
Y311760D01*
X189974Y311300D01*
X188924D01*
X188464Y311760D01*
Y314180D01*
X187887Y314757D01*
X186077D01*
X185400Y315434D01*
Y316227D01*
X185900Y316727D01*
X187887D01*
X188464Y317304D01*
Y323323D01*
X187787Y324000D01*
X186994D01*
X186494Y323500D01*
Y319220D01*
X185917Y318643D01*
X181179D01*
G01X187220Y345925D02*
Y342740D01*
X181680Y337200D01*
X179550D01*
X178000Y338750D01*
G01D02*
X175690Y336440D01*
X170077D01*
G01X176700Y349975D02*
X172800D01*
G01X170000Y359838D02*
Y358999D01*
X172800Y356199D01*
Y354646D01*
G01D02*
Y349975D01*
G01X171400Y450600D02*
X172491Y445121D01*
X178682Y430173D01*
G01D02*
X181697Y422894D01*
X181925Y422800D01*
G01X172530Y420950D02*
X174830Y423250D01*
Y427848D01*
G01D02*
Y435077D01*
X169500Y447945D01*
Y451401D01*
X170295Y452196D01*
Y466378D01*
G01X167865Y427771D02*
X168666Y429706D01*
X172060Y433100D01*
G01X221500Y64425D02*
X213589Y56514D01*
X202536D01*
X196290Y62760D01*
Y72590D01*
X204000Y80300D01*
Y84900D01*
X192800Y96100D01*
Y101000D01*
X191300Y102500D01*
X188400D01*
X187400Y101500D01*
G01X188980Y93385D02*
X193280D01*
X194600Y92065D01*
Y89900D01*
G01D02*
Y88400D01*
X193650Y87450D01*
X187803D01*
G01X185470Y96525D02*
Y96770D01*
X187700Y99000D01*
G01X188980Y93385D02*
X185480D01*
X185470Y93375D01*
G01X200000Y111925D02*
Y106401D01*
X196200Y102601D01*
Y96700D01*
X206900Y86000D01*
Y75100D01*
X200900Y69100D01*
Y64900D01*
X204300Y61500D01*
Y60600D01*
G01X196000Y111925D02*
X194500Y110425D01*
Y106200D01*
G01D02*
Y96300D01*
X205300Y85500D01*
Y76200D01*
X198300Y69200D01*
Y64200D01*
X201500Y61000D01*
G01X196000Y115075D02*
X197400Y116475D01*
Y121175D01*
X195500Y123075D01*
G01X187431Y123062D02*
X189470Y125101D01*
Y127104D01*
X187435Y129139D01*
Y129623D01*
G01D02*
X187452Y129606D01*
X188786D01*
X189318Y130138D01*
Y134143D01*
X188536Y134925D01*
X187000D01*
G01X191482Y129294D02*
Y131219D01*
X191000Y131701D01*
Y134925D01*
G01X191434Y123062D02*
Y129246D01*
X191482Y129294D01*
G01X195000Y134925D02*
X193700Y133625D01*
Y131577D01*
X195983Y129294D01*
G01D02*
Y123558D01*
X195500Y123075D01*
G01X187172Y143672D02*
X188066D01*
X191497Y147103D01*
Y149574D01*
X194853Y152930D01*
Y158074D01*
X195713Y158934D01*
Y160382D01*
X196609Y161278D01*
X197901D01*
X198823Y162200D01*
Y167152D01*
X199334Y167663D01*
X201926D01*
X203542Y166047D01*
G01X196332Y146991D02*
Y147231D01*
X198360Y149259D01*
Y153458D01*
X200054Y155161D01*
Y158042D01*
X200393Y159748D01*
G01X196577Y141185D02*
Y143596D01*
X196332Y143841D01*
G01X197243Y159748D02*
Y158763D01*
X195713Y157233D01*
Y151581D01*
X193057Y148925D01*
Y146456D01*
X187000Y140399D01*
Y138075D01*
G01X189300Y148400D02*
X189937Y149037D01*
Y150222D01*
X190870Y151155D01*
Y153438D01*
X193900Y156468D01*
Y159554D01*
X194094Y159748D01*
G01X200393Y162898D02*
Y161923D01*
X198825Y160355D01*
Y155934D01*
X196600Y153709D01*
Y150099D01*
X194617Y148116D01*
Y145718D01*
X194100Y145201D01*
Y141175D01*
X191000Y138075D01*
G01X195000D02*
X196225Y139300D01*
X197400D01*
X198534Y140434D01*
Y146909D01*
X200400Y148775D01*
Y151600D01*
G01X184645Y200655D02*
X186600Y202610D01*
Y204876D01*
X188500Y206776D01*
Y206875D01*
G01X184952Y238444D02*
X184861Y238353D01*
Y236694D01*
X190700Y230855D01*
Y227600D01*
X192448Y225852D01*
X194094D01*
G01X203542Y219553D02*
X202787Y220308D01*
X202476D01*
X201701Y221083D01*
X199726D01*
X198799Y222010D01*
Y223370D01*
X197902Y224267D01*
X196119D01*
X195669Y224717D01*
Y226701D01*
X194988Y227382D01*
X193128D01*
X191600Y228910D01*
Y231234D01*
X186700Y236134D01*
Y244458D01*
X187053Y244811D01*
Y247637D01*
X188500Y249084D01*
Y250175D01*
G01X194729Y242978D02*
Y241833D01*
X193057Y240161D01*
X192600Y239058D01*
Y237377D01*
X191693Y236470D01*
Y236370D01*
G01X203542Y225852D02*
X201941Y227453D01*
X199289D01*
X198839Y227903D01*
Y229962D01*
X198238Y230563D01*
X196534D01*
X195713Y231384D01*
Y232921D01*
X194838Y233796D01*
X191504D01*
X189820Y235480D01*
Y237492D01*
X190693Y239600D01*
Y242978D01*
G01X192501Y250182D02*
X190527Y248208D01*
X189831D01*
X188613Y246990D01*
Y244164D01*
X188260Y243811D01*
Y235791D01*
X192569Y231482D01*
Y231077D01*
X193046Y230600D01*
X194957D01*
X195669Y229888D01*
Y228217D01*
X196464Y227422D01*
X197985D01*
X198817Y226590D01*
Y224901D01*
X199451Y224267D01*
X201443D01*
X202000Y223710D01*
Y222001D01*
X202833Y221168D01*
X205157D01*
X206692Y222703D01*
G01X188500Y253325D02*
X189225D01*
X190800Y254900D01*
Y256840D01*
X191360Y257400D01*
X193084D01*
G01X188500Y253325D02*
Y254001D01*
X189300Y254801D01*
Y257900D01*
X187865Y259335D01*
X187070D01*
G01X194567Y255288D02*
X192951D01*
X192501Y254838D01*
Y253332D01*
G01X194567Y255288D02*
X195490Y256211D01*
Y258370D01*
X194600Y259260D01*
X190340D01*
X189510Y260090D01*
Y261948D01*
X190265Y263770D01*
Y267000D01*
G01X183625Y273500D02*
Y278900D01*
X183325Y279200D01*
G01X182435Y281797D02*
X182732Y281500D01*
X185299D01*
X186475Y280324D01*
Y279200D01*
G01X192380Y291900D02*
Y292916D01*
X190200Y295096D01*
X189961D01*
G01X186811D02*
X186798Y295083D01*
Y291172D01*
G01X198925Y300400D02*
X194294D01*
G01D02*
X192204Y302490D01*
X190465D01*
X188275Y300300D01*
G01X191199Y300200D02*
X193239Y298160D01*
X205810D01*
X206430Y298780D01*
G01X197155Y314223D02*
X199700Y311678D01*
Y309701D01*
X200995Y308406D01*
X204179D01*
G01X187180Y329590D02*
X189210D01*
X190420Y330800D01*
X199146D01*
X199376Y331030D01*
X201224D01*
X201454Y330800D01*
X214900D01*
X216405Y332305D01*
Y335970D01*
G01X187570Y337590D02*
Y341031D01*
X190465Y343926D01*
Y344426D01*
G01X200675Y342250D02*
X198851D01*
X195880Y345221D01*
Y346187D01*
X195500Y346567D01*
Y346775D01*
X193800Y348475D01*
G01X194800Y341700D02*
X197750Y338750D01*
X200675D01*
G01X190965Y348090D02*
X189189D01*
X187220Y346121D01*
Y345925D01*
G01X191408Y357451D02*
X193128D01*
X195859Y354720D01*
X198205D01*
X200175Y352750D01*
G01X193800Y348475D02*
Y350106D01*
X194200Y350506D01*
Y351930D01*
G01D02*
X191420Y354710D01*
G01X202240Y378980D02*
Y377640D01*
X196680Y372080D01*
X196641D01*
X195570Y371009D01*
Y370970D01*
X195380Y370780D01*
Y366550D01*
X198680Y363250D01*
X200175D01*
G01X197660Y390870D02*
X194930D01*
X191210Y394590D01*
X188810D01*
X186834Y396566D01*
X184296D01*
G01Y394007D02*
X186693D01*
X188430Y392270D01*
X190100D01*
G01X184296Y401685D02*
X189653D01*
X191867Y403899D01*
Y403995D01*
X191843D01*
G01X184296Y404244D02*
X188101D01*
X190109Y406252D01*
X194409D01*
X197300Y403361D01*
Y402000D01*
X198900Y400400D01*
X205300D01*
X212300Y393400D01*
X218123D01*
X232367Y399300D01*
X244280D01*
X246380Y397200D01*
Y383451D01*
X247180Y382651D01*
Y374881D01*
X245029Y372730D01*
X243700D01*
G01X200222Y398150D02*
X205350D01*
X206200Y397300D01*
Y394999D01*
X205301Y394100D01*
X203970D01*
X203393Y393523D01*
Y391183D01*
X203870Y390706D01*
X211323D01*
X211900Y390129D01*
Y389313D01*
X211323Y388736D01*
X204070D01*
X203393Y388059D01*
Y384077D01*
X202816Y383500D01*
X202000D01*
X201423Y384077D01*
Y393523D01*
X200846Y394100D01*
X194900D01*
X193270Y395730D01*
Y399270D01*
X192810Y399730D01*
X188130D01*
X187525Y399125D01*
X184296D01*
G01X199880Y402846D02*
X195014Y407712D01*
X188981D01*
X188072Y406803D01*
X184296D01*
G01Y409362D02*
X189540D01*
X190140Y409962D01*
X190270D01*
G01D02*
X192203D01*
X192491Y410250D01*
X194475D01*
G01X189766Y432050D02*
X191900Y434184D01*
Y444701D01*
X197400Y450201D01*
Y460800D01*
X197894Y461294D01*
Y465590D01*
G01X195532D02*
Y458983D01*
X195700Y458815D01*
Y450900D01*
X189838Y445038D01*
Y434910D01*
G01X186720Y432490D02*
Y444221D01*
X194000Y451501D01*
Y457501D01*
X193169Y458332D01*
Y466378D01*
G01X184480Y429370D02*
Y444281D01*
X189950Y449751D01*
Y457550D01*
X191500Y459100D01*
Y461001D01*
X190807Y461694D01*
Y465590D01*
G01X186300Y448700D02*
X188390Y450790D01*
Y458011D01*
X187700Y458701D01*
Y461299D01*
X188445Y462044D01*
Y465590D01*
G01X186083Y466378D02*
Y458018D01*
X186830Y457271D01*
Y453030D01*
X185300Y451500D01*
X185000D01*
G01X204100Y67400D02*
Y69840D01*
X214800Y80540D01*
Y104400D01*
X213600Y105600D01*
Y112400D01*
X218600Y117400D01*
X223300D01*
G01X199500Y123075D02*
X201770Y120805D01*
Y116241D01*
X204504Y113507D01*
G01X200000Y115075D02*
X201568Y113507D01*
X204504D01*
G01X204000Y123075D02*
X202524D01*
X202000Y123599D01*
Y126879D01*
X204056Y128935D01*
G01D02*
X202100Y130891D01*
Y134125D01*
X202900Y134925D01*
G01X211370Y123095D02*
X212757Y124482D01*
Y127064D01*
G01X208576Y128957D02*
X206600Y130933D01*
Y134425D01*
X207000Y134825D01*
G01X200000Y128764D02*
X198000Y130764D01*
Y133825D01*
X199000Y134825D01*
G01X200000Y128764D02*
Y123575D01*
X199500Y123075D01*
G01X207800D02*
X208500Y123775D01*
Y126057D01*
G01D02*
X210600Y128157D01*
Y132968D01*
X210800Y133168D01*
Y134794D01*
G01X207000Y137975D02*
X207500Y138475D01*
Y141000D01*
X208622Y142122D01*
Y142905D01*
X208627Y142910D01*
Y145499D01*
X208622Y145504D01*
Y145872D01*
X208627Y145877D01*
Y148416D01*
X207500Y149543D01*
Y154799D01*
X208252Y155551D01*
Y157239D01*
X209192Y158179D01*
X209842Y159748D01*
G01X206912Y147264D02*
X205800Y148376D01*
Y154606D01*
X205086Y156331D01*
Y157229D01*
X206017Y158160D01*
X207360D01*
X208240Y159040D01*
Y161350D01*
X206692Y162898D01*
G01X202900Y138075D02*
X202247Y138728D01*
Y145400D01*
G01D02*
X203940Y147091D01*
Y153441D01*
X204100Y153601D01*
Y157797D01*
X205140Y158837D01*
Y161300D01*
X203542Y162898D01*
G01X205598Y140480D02*
Y140500D01*
X205568Y140530D01*
Y142770D01*
X206912Y144114D01*
G01X209842Y162898D02*
X210436Y161464D01*
X211400Y160500D01*
Y153100D01*
X211300Y152859D01*
Y151100D01*
G01X214500Y138075D02*
X214900Y138475D01*
Y140670D01*
X215180Y141350D01*
Y144437D01*
X214619Y145791D01*
X211860Y148550D01*
Y149748D01*
X211300Y151100D01*
G01X203542Y159748D02*
Y158472D01*
X202675Y157605D01*
Y153576D01*
X202380Y153281D01*
Y148547D01*
X200103Y146270D01*
Y138995D01*
X199083Y137975D01*
X199000D01*
G01X200400Y151600D02*
Y153000D01*
X201299Y153899D01*
Y157997D01*
X201996Y158694D01*
Y164444D01*
X200393Y166047D01*
G01X209842Y153449D02*
Y152441D01*
X209200Y151799D01*
Y150050D01*
X210187Y149063D01*
Y148016D01*
X213296Y144907D01*
X213620Y144125D01*
Y141659D01*
X213340Y140979D01*
Y140956D01*
X213300Y140859D01*
Y140168D01*
X212689Y138689D01*
X211944Y137944D01*
X210800D01*
G01X209842Y166047D02*
X211398Y164491D01*
Y162202D01*
X212940Y160660D01*
Y153743D01*
X213440Y153243D01*
Y149177D01*
X215942Y146675D01*
X216740Y144750D01*
Y143566D01*
X218900Y141406D01*
Y139599D01*
X218500Y139199D01*
Y138075D01*
G01X212100Y247225D02*
Y245244D01*
X211478Y244622D01*
Y238185D01*
X211709Y237628D01*
X212421Y236916D01*
Y233880D01*
X211432Y232891D01*
Y224293D01*
X209842Y222703D01*
G01X198990Y241937D02*
Y240349D01*
X198839Y240198D01*
Y237255D01*
G01X200393Y229002D02*
Y229986D01*
X198811Y231568D01*
Y237227D01*
X198839Y237255D01*
G01X202990Y241937D02*
Y240809D01*
X201989Y239808D01*
Y237255D01*
G01D02*
X201960Y237226D01*
Y230584D01*
X203542Y229002D01*
G01X207610Y242910D02*
Y240200D01*
X208027Y239783D01*
Y234214D01*
X207207Y233394D01*
X206692Y232151D01*
G01X206200Y255385D02*
X208716D01*
X209071Y255030D01*
X211459D01*
X212530Y253959D01*
Y250805D01*
X212100Y250375D01*
G01X200460Y250185D02*
X202645Y248000D01*
X203373D01*
X206010Y245363D01*
Y244510D01*
X207610Y242910D01*
G01X204000Y261025D02*
X205623D01*
X206573Y261975D01*
X208500D01*
G01X214034Y261482D02*
X213852Y261300D01*
X209175D01*
X208500Y261975D01*
G01X205900Y266130D02*
X204930D01*
X204000Y265200D01*
Y264175D01*
G01X198925Y300400D02*
Y306128D01*
X197853Y307200D01*
G01X218500Y318800D02*
X214121D01*
X213660Y318339D01*
Y317903D01*
X213383Y317235D01*
X212061Y315913D01*
X204350D01*
X204179Y316084D01*
G01Y313524D02*
X210770D01*
G01X204179Y310965D02*
X214035D01*
X217420Y307580D01*
X219220D01*
G01X236688Y311217D02*
X236700D01*
Y312770D01*
X231970Y317500D01*
X227635D01*
X227175Y317960D01*
Y321923D01*
X226598Y322500D01*
X225782D01*
X225205Y321923D01*
Y310177D01*
X224628Y309600D01*
X223812D01*
X223235Y310177D01*
Y312242D01*
X222658Y312819D01*
X219560D01*
X219100Y313279D01*
Y314329D01*
X219560Y314789D01*
X222390D01*
X223235Y315634D01*
Y321923D01*
X222658Y322500D01*
X221101D01*
X218243Y325358D01*
X213758D01*
X209602Y321202D01*
X204179D01*
G01X208628Y324665D02*
X207724Y323761D01*
X204179D01*
G01Y318643D02*
X210930D01*
G01X217300Y322800D02*
X216200D01*
X214600Y321200D01*
X213199D01*
X210930Y318931D01*
Y318643D01*
G01X200175Y345750D02*
X198642D01*
X197775Y346617D01*
G01X214175Y333740D02*
X213855Y333420D01*
X202440D01*
G01X203325Y345750D02*
Y349250D01*
G01X203825Y338750D02*
X204375Y338200D01*
X208300D01*
G01D02*
X211000Y340900D01*
Y343399D01*
X211874Y344273D01*
X215420D01*
G01Y346832D02*
X211912D01*
X208315Y343235D01*
G01D02*
X207330Y342250D01*
X203825D01*
G01X200175Y356250D02*
X199865Y356560D01*
X197450D01*
G01X215420Y351950D02*
X209750D01*
X208340Y353360D01*
G01D02*
X207730Y352750D01*
X203325D01*
G01X215420Y354510D02*
X212210D01*
X208350Y358370D01*
G01D02*
X205445D01*
X203325Y356250D01*
G01Y363250D02*
Y359750D01*
G01X208120Y363410D02*
X211470Y360060D01*
Y357529D01*
X211930Y357069D01*
X215420D01*
G01X203325Y359750D02*
X204460D01*
X208120Y363410D01*
G01X197711Y349250D02*
X200175D01*
G01X203325D02*
X204949D01*
X205908Y348291D01*
X208320D01*
G01D02*
X210592D01*
X211692Y349391D01*
X215420D01*
G01X200175Y367250D02*
X199825Y367600D01*
X197400D01*
G01X200175Y370750D02*
X199675Y370250D01*
X197400D01*
G01X215420Y362187D02*
X213012D01*
X209580Y365619D01*
Y368520D01*
X208350Y369750D01*
G01D02*
X205850Y367250D01*
X203325D01*
G01X210550Y375290D02*
X206130D01*
X203325Y372485D01*
Y370750D01*
G01X215420Y364746D02*
X213054D01*
X211160Y366640D01*
Y371240D01*
X210550Y371850D01*
Y375290D01*
G01X230063Y386260D02*
Y381853D01*
X227190Y378980D01*
X202240D01*
G01X223800Y50700D02*
X232400D01*
X234990Y53290D01*
Y57613D01*
G01X230925Y71000D02*
X229000D01*
X226000Y68000D01*
G01D02*
X221925D01*
X221500Y67575D01*
G01X224330Y83210D02*
Y91831D01*
X225924Y93425D01*
X227500D01*
G01X226887Y117297D02*
X227706Y116478D01*
X230067Y115500D01*
X232060D01*
X234355Y113205D01*
Y108355D01*
X232900Y106900D01*
Y103244D01*
X234155Y101989D01*
Y100235D01*
X235684Y98706D01*
X237395D01*
X238530Y99841D01*
Y100159D01*
X239871Y101500D01*
X246700D01*
X250200Y98000D01*
X254600D01*
X255100Y98500D01*
X256500D01*
G01X215294Y123101D02*
Y127326D01*
X217262Y129294D01*
G01D02*
X219198Y131230D01*
Y133227D01*
X218500Y133925D01*
Y134925D01*
G01X221278Y129294D02*
X223200Y131216D01*
Y134378D01*
X222653Y134925D01*
X222500D01*
G01X219313Y123101D02*
Y127329D01*
X221278Y129294D01*
G01X225284D02*
X227500Y131510D01*
Y132798D01*
X227000Y133298D01*
Y134425D01*
X226500Y134925D01*
G01X223338Y123101D02*
Y127348D01*
X225284Y129294D01*
G01X212757Y127064D02*
X214778Y129085D01*
Y133020D01*
X214500Y133298D01*
Y134925D01*
G01X228766Y142545D02*
X228582Y142621D01*
X228058Y143885D01*
X221683Y150260D01*
Y151117D01*
X218800Y154000D01*
X217800D01*
X216740Y155060D01*
Y160616D01*
X217700Y161576D01*
Y163600D01*
X218600Y164500D01*
X220800D01*
X222402Y162898D01*
G01X219253Y166047D02*
X218246D01*
X216700Y164501D01*
Y161793D01*
X215880Y160973D01*
Y154619D01*
X217957Y152542D01*
X217973Y152536D01*
X218554Y151131D01*
X218631D01*
G01D02*
X218881Y151027D01*
X219356Y149882D01*
X226460Y142778D01*
Y142440D01*
X226490Y142410D01*
Y141109D01*
X227599Y140000D01*
X228575D01*
X230500Y138075D01*
G01X221400Y142600D02*
X222500Y141500D01*
Y138075D01*
G01X219253Y169197D02*
X217621Y168521D01*
X214600Y165500D01*
Y162200D01*
X213800Y161400D01*
Y154100D01*
X215000Y152900D01*
Y149824D01*
X217265Y147559D01*
X218300Y145061D01*
Y144500D01*
X220200Y142600D01*
X221400D01*
G01X226500Y138075D02*
X224900Y139675D01*
Y142131D01*
X220931Y146100D01*
X220500D01*
X219600Y147000D01*
G01D02*
Y147431D01*
X216560Y150471D01*
Y152722D01*
X215020Y154262D01*
Y161330D01*
X215600Y161910D01*
Y164771D01*
X218432Y167603D01*
X220846D01*
X222402Y166047D01*
G01X223000Y153967D02*
Y153880D01*
X223901Y152979D01*
X224312Y151987D01*
X230396Y145903D01*
X234840Y144061D01*
X238753Y140148D01*
Y127996D01*
X243609Y123140D01*
G01X219253Y162898D02*
Y161912D01*
X217600Y160259D01*
Y156088D01*
X218619Y155069D01*
X219082D01*
X229602Y144550D01*
X233779Y142822D01*
X237000Y139601D01*
Y129174D01*
X236623Y128797D01*
G01X239118Y145170D02*
X236065Y148223D01*
Y148486D01*
X226379Y158172D01*
X224798D01*
X223953Y159017D01*
Y161299D01*
X225552Y162898D01*
G01Y166047D02*
X225965Y165634D01*
X226433Y164505D01*
X227082Y163532D01*
Y159626D01*
X227439Y158764D01*
X234803Y151400D01*
X235993Y150907D01*
X237603Y149297D01*
X240139Y148246D01*
X244827Y143558D01*
X246019Y140680D01*
X247601Y139098D01*
X248866Y137205D01*
X249900Y134708D01*
X250436Y132013D01*
X250824Y131077D01*
X252149Y129752D01*
X252275Y129700D01*
X252600Y129375D01*
G01X223000Y153967D02*
Y153996D01*
X222703D01*
X220829Y155870D01*
Y158172D01*
X219253Y159748D01*
G01X223007Y153967D02*
X223000D01*
G01X222402Y159748D02*
Y158763D01*
X223932Y157233D01*
Y157209D01*
X223933Y157208D01*
Y156054D01*
X224918Y155069D01*
X227077D01*
X229621Y152525D01*
Y148634D01*
X231219Y147036D01*
X235611Y145215D01*
X235800Y145026D01*
X236437Y144762D01*
X240300Y140899D01*
Y139387D01*
X241743Y137944D01*
X241826D01*
G01X217000Y233800D02*
Y231007D01*
X216141Y230148D01*
Y222703D01*
G01X213245Y238825D02*
X213552Y238698D01*
X213576Y238640D01*
X214700Y232989D01*
Y224449D01*
X212991Y222740D01*
G01X235070Y236989D02*
Y231947D01*
X236651Y230366D01*
Y228398D01*
X235685Y227432D01*
X234082D01*
X233480Y226830D01*
X233440D01*
Y225259D01*
X232488Y224307D01*
X228175D01*
X226588Y222720D01*
X225590D01*
G01X223269Y237825D02*
Y236169D01*
X220958Y233858D01*
Y231428D01*
X220109Y230579D01*
X218564D01*
X217700Y229715D01*
Y221188D01*
X216103Y219591D01*
G01X219253Y219553D02*
X220841Y221141D01*
Y223718D01*
X221406Y224283D01*
X223245D01*
X223977Y225015D01*
Y231524D01*
X225250Y232797D01*
Y234250D01*
X226500Y235500D01*
Y242500D01*
X227137Y243137D01*
Y248201D01*
X227116Y248222D01*
Y249849D01*
G01X219290Y225852D02*
X220841Y227403D01*
Y229661D01*
X222042Y230862D01*
Y232419D01*
X223434Y233811D01*
Y234933D01*
X225000Y236499D01*
Y242000D01*
X223300Y243700D01*
Y245075D01*
X222575Y245800D01*
G01X221000Y243000D02*
Y241694D01*
X221719Y240975D01*
X223269D01*
G01X217200Y241775D02*
X216076D01*
X215400Y241099D01*
Y237683D01*
X215954Y236346D01*
X217000Y235300D01*
Y233800D01*
G01X217200Y241775D02*
X217761Y242336D01*
Y247761D01*
X218700Y248700D01*
X219710D01*
X220900Y249890D01*
Y257325D01*
X219900Y258325D01*
G01X220100Y237200D02*
X218675Y238625D01*
X217200D01*
G01X227820Y233900D02*
Y231270D01*
X225552Y229002D01*
G01X215100Y244100D02*
X213705D01*
X213245Y243640D01*
Y241975D01*
G01X223100Y249225D02*
X222675Y248800D01*
X221875D01*
X221026Y247951D01*
Y247225D01*
X219601Y245800D01*
X219425D01*
G01X216800Y255550D02*
X214175D01*
X214100Y255625D01*
G01X216800Y255550D02*
X218240D01*
X218800Y254990D01*
Y253635D01*
G01X215510Y253310D02*
Y251290D01*
X216223Y250577D01*
X218708D01*
X218800Y250485D01*
G01X219900Y267100D02*
X219053Y266253D01*
Y265601D01*
X219730Y264924D01*
Y262018D01*
X219731Y261643D01*
X219900Y261475D01*
G01X225363Y261675D02*
Y263462D01*
X223400Y265425D01*
G01Y268575D02*
X225325D01*
X226405Y267495D01*
Y266335D01*
G01X231689Y334896D02*
X231700D01*
Y334900D01*
X229800D01*
X223030Y328130D01*
X216250D01*
G01X221000Y352000D02*
X223300Y349700D01*
Y342175D01*
X221925Y340800D01*
X219900D01*
X218986Y341714D01*
X215420D01*
G01X257046Y331377D02*
X251123Y337300D01*
X230082D01*
X226127Y333345D01*
X223755D01*
X217945Y339155D01*
X215420D01*
G01Y359628D02*
X225828D01*
X228540Y362340D01*
Y370460D01*
X225815Y373185D01*
Y374564D01*
X223920Y376459D01*
Y376635D01*
G01X228680D02*
X223920D01*
G01X226240Y465590D02*
Y454659D01*
X227560Y453339D01*
Y440053D01*
X226830Y439323D01*
Y435170D01*
G01X223878Y465590D02*
Y460923D01*
X224180Y460621D01*
Y455280D01*
X226000Y450886D01*
Y442115D01*
X225000Y439700D01*
Y433100D01*
G01X219250Y422150D02*
X216525D01*
X215800Y422875D01*
G01X234990Y57613D02*
X234100Y58503D01*
Y66600D01*
X239100Y71600D01*
Y73810D01*
X233453Y79457D01*
G01X240000Y67400D02*
X242025Y69425D01*
Y71900D01*
G01X230925Y71000D02*
Y65812D01*
X231250Y65487D01*
G01X247953Y79457D02*
Y79537D01*
X245490Y82000D01*
X235900D01*
X233453Y79553D01*
Y79457D01*
G01X227500Y93425D02*
Y88520D01*
X227547Y88473D01*
Y86543D01*
G01X242047D02*
Y84067D01*
X241340Y83360D01*
X235336D01*
X234456Y82480D01*
X232150D01*
G01X241700Y93925D02*
Y92294D01*
X242000Y91994D01*
Y88520D01*
X242047Y88473D01*
Y86543D01*
G01X227760Y82524D02*
X228054Y82230D01*
X228778D01*
X230500Y80508D01*
Y79457D01*
G01X236648Y100739D02*
X244082Y108173D01*
G01X235880Y115000D02*
Y116279D01*
X237833Y118232D01*
Y122588D01*
X237412Y123009D01*
X235602D01*
X235510Y123101D01*
G01X236425Y109760D02*
Y114455D01*
X235880Y115000D01*
G01X234500Y117500D02*
X235510Y118510D01*
Y119951D01*
G01X239900Y117550D02*
Y117650D01*
X239700Y117850D01*
Y119841D01*
X239590Y119951D01*
G01X234900Y126100D02*
Y124211D01*
X235510Y123601D01*
Y123101D01*
G01X231415D02*
X233000Y124686D01*
Y128883D01*
X233511Y129394D01*
Y129594D01*
G01D02*
X233711D01*
X235426Y131309D01*
Y133999D01*
X234500Y134925D01*
Y135125D01*
G01X229342Y129240D02*
X231300Y131198D01*
Y134100D01*
X230500Y134900D01*
Y134925D01*
G01X227370Y123101D02*
Y127268D01*
X229342Y129240D01*
G01X242500Y129000D02*
X240400Y131100D01*
Y133368D01*
X241826Y134794D01*
G01X236623Y128797D02*
Y127277D01*
X239590Y124310D01*
Y123101D01*
G01X228702Y159748D02*
X230268Y158182D01*
X232433D01*
X233411Y157204D01*
Y155841D01*
X234226Y155026D01*
X235806D01*
X237110Y153722D01*
Y152094D01*
X238273Y150931D01*
X239661D01*
X247121Y143471D01*
X247512Y142528D01*
G01X234500Y138275D02*
X234416D01*
X231791Y140900D01*
X230411D01*
X228766Y142545D01*
G01X245836Y137944D02*
X245752D01*
X244338Y139358D01*
Y140660D01*
X243504Y142674D01*
X242313Y143865D01*
X240423D01*
X239118Y145170D01*
G01X256333Y123101D02*
Y127658D01*
X255200Y128791D01*
Y133375D01*
X254985Y133590D01*
Y138252D01*
X253662Y139575D01*
X251249D01*
X249883Y140941D01*
X249700Y141216D01*
Y143500D01*
X248562Y144638D01*
X248350D01*
X239624Y153364D01*
Y154064D01*
G01X248988Y157001D02*
X247789Y158200D01*
X243613D01*
X242869Y158944D01*
Y160412D01*
X241981Y161300D01*
X240700D01*
X239102Y162898D01*
X238150D01*
G01X231851Y159748D02*
X232837D01*
X234399Y158186D01*
X235713D01*
X236613Y157286D01*
Y155478D01*
X238027Y154064D01*
X239624D01*
G01X235001Y162898D02*
X236546Y161353D01*
X238746D01*
X239700Y160399D01*
Y159036D01*
X244850Y153886D01*
Y153350D01*
G01X235001Y159748D02*
X236627Y159074D01*
X237501Y158200D01*
X238800D01*
X241554Y155446D01*
Y153598D01*
X247452Y147700D01*
X248062D01*
X252586Y143176D01*
Y142376D01*
G01X230520Y238825D02*
Y233526D01*
X230320Y233043D01*
Y227433D01*
X228739Y225852D01*
G01X259000Y237600D02*
Y236999D01*
X259700Y236299D01*
Y231699D01*
X258001Y230000D01*
X256900D01*
X255512Y228612D01*
Y228329D01*
X254583Y227400D01*
X243724D01*
X242922Y226598D01*
Y224911D01*
X242011Y224000D01*
X240418D01*
X239121Y222703D01*
X238150D01*
G01X264100Y235500D02*
Y233400D01*
X258800Y228100D01*
X256500D01*
X252300Y223900D01*
Y221800D01*
X251662Y221162D01*
X233460D01*
X231889Y219591D01*
G01Y222740D02*
X233515Y223414D01*
X234450Y224349D01*
X235758D01*
X236651Y225242D01*
Y226748D01*
X238385Y228482D01*
Y232466D01*
G01X247700Y229400D02*
X246521Y230579D01*
X240264D01*
X239728Y230043D01*
Y224970D01*
X239072Y224314D01*
X237528D01*
X236602Y223388D01*
X235038Y222740D01*
G01X238413Y241964D02*
Y239474D01*
X237065Y236211D01*
Y233786D01*
X238385Y232466D01*
G01X235100Y251725D02*
X233126Y249751D01*
Y233929D01*
X233600Y233455D01*
Y230751D01*
X231851Y229002D01*
G01X239100Y250625D02*
X236924D01*
X235068Y248769D01*
Y238898D01*
X235070Y236989D01*
G01X231250Y247375D02*
X229274D01*
X228600Y246701D01*
Y242699D01*
X227820Y241919D01*
Y233900D01*
G01X230520Y241975D02*
X230535Y241990D01*
Y244564D01*
G01X237700Y257387D02*
X235560D01*
X235100Y256927D01*
Y254875D01*
G01X227316Y256700D02*
Y253199D01*
X227116Y252999D01*
G01X237730Y248085D02*
X237805Y248010D01*
Y245722D01*
X238413Y245114D01*
G01X238531Y263081D02*
X239930Y261682D01*
Y254605D01*
X239100Y253775D01*
G01X231250Y250525D02*
X230000Y251775D01*
Y255700D01*
G01X229630Y264404D02*
Y263878D01*
X229265Y262996D01*
Y261998D01*
G01X241188Y279347D02*
X243014D01*
X244445Y280778D01*
X250252D01*
G01X232225Y306900D02*
Y310940D01*
X231065Y312100D01*
X228800D01*
G01X238400Y304200D02*
X240000Y302600D01*
X258400D01*
X260500Y300500D01*
G01X235375Y306900D02*
X233275Y304800D01*
X229500D01*
X228800Y305500D01*
G01X238420Y344273D02*
X236138D01*
X233500Y346911D01*
G01X238420Y341714D02*
X235977D01*
X233780Y343911D01*
X233500D01*
G01X254340Y346320D02*
X252460Y348200D01*
X249700D01*
X242700Y355200D01*
Y357710D01*
X240782Y359628D01*
X238420D01*
G01Y357069D02*
X236209D01*
X233650Y359628D01*
G01X256320Y341490D02*
X254646D01*
X241626Y354510D01*
X238420D01*
G01Y351950D02*
X234350D01*
X233800Y352500D01*
Y354300D01*
G01X261300Y334100D02*
Y336161D01*
X258381Y339080D01*
X254899D01*
X244588Y349391D01*
X238420D01*
G01X256124Y336355D02*
X245647Y346832D01*
X238420D01*
G01X228680Y376635D02*
X231290D01*
X233825Y374100D01*
G01X245300Y361100D02*
Y363200D01*
X243754Y364746D01*
X238420D01*
G01X245400Y355800D02*
Y357100D01*
X242800Y359700D01*
Y361301D01*
X241914Y362187D01*
X238420D01*
G01X245430Y367305D02*
X238420D01*
G01X233600Y377300D02*
Y378680D01*
X234815Y379895D01*
G01D02*
X237630D01*
X239305Y378220D01*
G01X237937Y390000D02*
X240575D01*
X243250Y392675D01*
G01Y385930D02*
X241570Y384250D01*
Y380330D01*
X242455Y379445D01*
Y378220D01*
G01X239500Y447750D02*
X238057Y449193D01*
Y466372D01*
X238051Y466378D01*
G01X230965Y465590D02*
Y461834D01*
X231700Y461099D01*
Y455200D01*
X232586Y454314D01*
X233230Y452760D01*
Y448741D01*
X231489Y447000D01*
X231250D01*
G01X235200Y449100D02*
Y447400D01*
X232970Y445170D01*
X230491D01*
X229300Y446361D01*
Y453870D01*
X230100Y454670D01*
Y460300D01*
X228602Y461798D01*
Y465590D01*
G01X235689D02*
Y456512D01*
X236221Y455980D01*
Y454400D01*
G01X233327Y465590D02*
Y457957D01*
X233844Y455356D01*
X235400Y451600D01*
G01X240413Y466378D02*
Y459045D01*
X242040Y457418D01*
Y451453D01*
X242096Y451396D01*
X241350Y450650D01*
X240200D01*
G01X256075Y51500D02*
Y55925D01*
X256000Y56000D01*
G01X253000Y75075D02*
Y77500D01*
G01X245000Y79457D02*
Y76600D01*
X242025Y73625D01*
Y71900D01*
G01X250000Y73000D02*
X250060D01*
X250800Y73740D01*
Y78300D01*
X252900Y80400D01*
G01X253000Y71925D02*
X251075D01*
X250000Y73000D01*
G01X254900Y92500D02*
Y89300D01*
X256900Y87300D01*
G01X252900Y80400D02*
X250890Y82410D01*
X247720D01*
X244208Y85922D01*
Y97302D01*
G01X256500Y98500D02*
X258270Y96730D01*
X262160D01*
X262990Y97560D01*
Y101690D01*
X263509Y102945D01*
X264657Y103712D01*
X265949D01*
X271138Y98523D01*
X283503D01*
X285680Y100700D01*
X289551D01*
X291100Y102249D01*
Y111600D01*
X287500Y115200D01*
Y117800D01*
X285960Y119340D01*
Y126940D01*
X285300Y127600D01*
Y132300D01*
X286687Y133687D01*
X309838D01*
X310200Y133325D01*
G01X245836Y137944D02*
Y137844D01*
X247349Y136331D01*
X248575Y133370D01*
Y132428D01*
X249300Y130677D01*
Y123279D01*
X249730Y122849D01*
Y121001D01*
X249440Y120711D01*
Y115839D01*
X248087Y114486D01*
Y113214D01*
G01X252111D02*
Y114890D01*
X251000Y116001D01*
Y120064D01*
X251290Y120354D01*
Y123496D01*
X250860Y123926D01*
Y127585D01*
X251313Y128038D01*
X251773D01*
X252600Y128865D01*
Y129375D01*
G01X253100Y119900D02*
Y124094D01*
X252600Y124594D01*
Y126225D01*
G01X245310Y113910D02*
X244800Y114420D01*
Y118799D01*
X243609Y119990D01*
G01X256100Y110025D02*
X259075D01*
X261800Y107300D01*
G01X245500Y127800D02*
Y125535D01*
X245960Y125075D01*
X247500D01*
G01X245836Y134794D02*
Y130916D01*
X245520Y130600D01*
G01X257422Y129840D02*
X256700Y131583D01*
Y134794D01*
G01X260346Y122601D02*
X261758D01*
X262218Y123061D01*
Y138802D01*
X261040Y139980D01*
X259870D01*
X255760Y144090D01*
Y144364D01*
X247500Y152624D01*
Y155513D01*
X248988Y157001D01*
G01X252374Y137944D02*
X250956D01*
X248826Y140074D01*
X247512Y142042D01*
Y142528D01*
G01D02*
X247546Y142562D01*
G01X244850Y153350D02*
X254400Y143800D01*
Y143526D01*
X259981Y137945D01*
X260200D01*
G01X252586Y142376D02*
X252824D01*
X256700Y138500D01*
Y137944D01*
G01X251354Y152877D02*
Y156501D01*
X253521Y158668D01*
Y158751D01*
G01X311158Y163487D02*
X310288Y162617D01*
G02X308696Y161957I-1593J1592D01*
G01X307994D01*
G02X306911Y162406I0J1531D01*
G01X299698Y169619D01*
G02X299038Y171211I1592J1593D01*
G01Y172511D01*
G03X297846Y175388I-4068J0D01*
G01X297570Y175664D01*
G03X295978Y176324I-1593J-1592D01*
G01X295312D01*
G02X293760Y176967I0J2195D01*
G01X293698Y177029D01*
G03X292146Y177672I-1552J-1552D01*
G01X288904D01*
G02X288059Y178022I0J1195D01*
G01X287764Y178317D01*
G03X287276Y178519I-488J-488D01*
G01X276697D01*
G03X275990Y177812I0J-707D01*
G01Y176557D01*
G02X275540Y176107I-450J0D01*
G01X274335D01*
G02X273887Y176293I1J634D01*
G01X273825Y176355D01*
G02X273639Y176804I449J449D01*
G01Y179337D01*
G03X273218Y180351I-1434J-1D01*
G03X271993Y180860I-1226J-1222D01*
G01X265089D01*
G02X262839Y183110I0J2250D01*
G01Y186012D01*
G03X261690Y187161I-1149J0D01*
G01X261600D01*
G03X260451Y186012I0J-1149D01*
G01Y178028D01*
G02X259292Y176869I-1159J0D01*
G01X259203D01*
G02X258044Y178028I0J1159D01*
G01Y186409D01*
G03X256876Y187577I-1168J0D01*
G01X256786D01*
G03X255618Y186409I0J-1168D01*
G01Y184045D01*
G02X253368Y181795I-2250J0D01*
G01X250749D01*
G01X267909Y185096D02*
X266873Y186132D01*
G02X266032Y188163I2031J2031D01*
G03X265485Y189483I-1866J0D01*
G01X265445Y189523D01*
G03X264617Y189866I-828J-828D01*
G01X261158D01*
G03X260014Y189392I0J-1618D01*
G02X259695Y189260I-319J319D01*
G01X252846D01*
G03X251255Y188601I0J-2250D01*
G01X250749Y188095D01*
G01X253001Y203097D02*
X252167Y202263D01*
X249626D01*
X249176Y201813D01*
Y199792D01*
X248480Y199096D01*
X246040D01*
X244450Y197506D01*
G01X250465Y242578D02*
Y240100D01*
X252165Y238400D01*
X254100D01*
X255518Y236982D01*
Y234582D01*
X254636Y233700D01*
X253100D01*
X252300Y232900D01*
Y231500D01*
X251400Y230600D01*
X248900D01*
X247700Y229400D01*
G01X259000Y237600D02*
Y239500D01*
X255832Y242668D01*
X254466D01*
G01X259500Y258800D02*
X255427Y254727D01*
Y246779D01*
X254466Y245818D01*
G01X250465Y245728D02*
X249910Y246283D01*
Y248562D01*
X250837Y250800D01*
X250900D01*
G01X253110Y254909D02*
X251839Y253637D01*
X250900Y251369D01*
Y250800D01*
G01X242690Y257700D02*
Y255300D01*
G01X247470Y269990D02*
Y267261D01*
X242690Y262481D01*
Y260850D01*
G01X253402Y280778D02*
Y276756D01*
G01Y280778D02*
X253900Y281276D01*
Y282000D01*
X256000Y284100D01*
Y292980D01*
X258100Y295080D01*
G01X253402Y276756D02*
X257181D01*
X257500Y277075D01*
G01X242592Y330683D02*
X245809Y333900D01*
X246000D01*
G01D02*
X249600D01*
X254520Y328980D01*
X264420D01*
X267200Y326200D01*
Y308400D01*
X266300Y307500D01*
G01X259420Y343230D02*
X257738Y344912D01*
X254340Y346320D01*
G01X259420Y340630D02*
X258560Y341490D01*
X256320D01*
G01X250225Y359100D02*
Y363100D01*
G01D02*
X247300D01*
X245300Y361100D01*
G01X250225Y355200D02*
Y351200D01*
G01Y355200D02*
X249625Y355800D01*
X245400D01*
G01X250300Y367725D02*
X249880Y367305D01*
X245430D01*
G01X243250Y392675D02*
Y385930D01*
G01X262190Y425300D02*
Y426790D01*
X250460Y438520D01*
Y460660D01*
X249862Y461258D01*
Y466378D01*
G01X257095Y428796D02*
X248878Y437013D01*
Y459522D01*
X247500Y460900D01*
Y466378D01*
G01X246700Y454100D02*
Y457092D01*
X245138Y460863D01*
Y466378D01*
G01X242776D02*
Y460024D01*
X243600Y459200D01*
Y452100D01*
X244200Y451500D01*
X246700D01*
G01X267939Y41122D02*
X264575Y44486D01*
Y49000D01*
G01X268500Y45500D02*
Y48925D01*
X268425Y49000D01*
G01X271575Y53000D02*
X272556Y53981D01*
X277641D01*
X279934Y51688D01*
G01X264575Y53000D02*
Y49000D01*
G01X259106Y66000D02*
Y55773D01*
X261425Y53454D01*
Y53000D01*
G01X268425Y57000D02*
Y53000D01*
G01D02*
Y49000D01*
G01X260050Y87026D02*
Y76610D01*
X259106Y75666D01*
Y66000D01*
G01X268537Y104703D02*
Y103943D01*
X271760Y100720D01*
X277410D01*
X278220Y101530D01*
G01X265801Y106040D02*
Y110599D01*
X261700Y114700D01*
G01X261800Y107300D02*
Y103795D01*
X261430Y102901D01*
Y99060D01*
X260970Y98600D01*
G01X274760Y105140D02*
X272124D01*
X271687Y104703D01*
G01X310200Y130175D02*
Y122150D01*
X306760Y118710D01*
X302590D01*
X301590Y117710D01*
Y113880D01*
X298210Y110500D01*
X296490D01*
X295320Y109330D01*
X294441D01*
X292660Y107549D01*
Y101602D01*
X290198Y99140D01*
X286327D01*
X284150Y96963D01*
X269758D01*
X264989Y101732D01*
G01X278394Y111035D02*
X274163Y115266D01*
Y116684D01*
X273481Y117366D01*
X271585D01*
G01X268256Y112794D02*
X273605D01*
X279969Y106430D01*
X281480D01*
X282261Y105649D01*
X286549D01*
G01X268537Y108226D02*
X268629Y108318D01*
Y109940D01*
X268256Y110313D01*
Y112794D01*
G01X260200Y132395D02*
Y134795D01*
G01X260388Y125001D02*
Y126874D01*
X257422Y129840D01*
G01X258500Y146400D02*
X260653Y144247D01*
X261863D01*
G01X322005Y183411D02*
X321769D01*
X319681Y181323D01*
G02X319340Y181043I-1592J1591D01*
G01X318183Y180270D01*
G02X317795Y180062I-1252J1869D01*
G01X316085Y179353D01*
G02X315223Y179182I-861J2081D01*
G01X314571D01*
G03X314124Y179123I-2J-1711D01*
G03X312792Y178352I778J-2881D01*
G01X312703Y178263D01*
G02X311281Y177674I-1422J1422D01*
G01X305057D01*
G02X302580Y178659I-1J3605D01*
G03X297295Y180848I-5285J-5285D01*
G01X279082D01*
G02X278662Y180886I-2J2313D01*
G02X276438Y181440I3341J18152D01*
G01X273567Y182347D01*
G02X273274Y182911I135J428D01*
G01X274253Y186006D01*
G03X274209Y186508I-626J198D01*
G01X274041Y186829D01*
G03X272650Y187264I-914J-480D01*
G01X272610Y187243D01*
G03X271917Y186418I650J-1250D01*
G01X271287Y184423D01*
G02X271052Y184026I-963J302D01*
G02X269836Y183526I-1176J1132D01*
G02X268925Y184080I681J2145D01*
G01X267909Y185096D01*
G01X264100Y235500D02*
Y240325D01*
X261800Y242625D01*
G01Y245775D02*
Y250300D01*
G01D02*
Y255300D01*
X263179Y256679D01*
Y262079D01*
X265200Y264100D01*
Y266400D01*
X264000Y267600D01*
X262730D01*
G01X259500Y263700D02*
Y258800D01*
G01X262100Y280700D02*
X261700Y281664D01*
Y283625D01*
X261800Y283725D01*
G01X266200Y294800D02*
X260500Y300500D01*
G01X261800Y286875D02*
X261500Y287175D01*
Y290440D01*
G01X277572Y351198D02*
X275500Y349126D01*
Y342884D01*
X263993Y331377D01*
X257046D01*
G01X263990Y378024D02*
Y380781D01*
X267225Y384016D01*
Y384100D01*
G01X261168Y398487D02*
X264661D01*
X268300Y394848D01*
Y388499D01*
X267225Y387424D01*
Y384100D01*
G01X265100Y395100D02*
X262150D01*
X261168Y396082D01*
Y398487D01*
G01X265400Y420625D02*
X262190Y423835D01*
Y425300D01*
G01X261400Y420625D02*
X258250Y423775D01*
Y427641D01*
X257095Y428796D01*
G01X277700Y412580D02*
X274980Y415300D01*
X267575D01*
X265400Y417475D01*
G01X277700Y406100D02*
X270600D01*
X261400Y415300D01*
Y417475D01*
G01X266727Y443185D02*
X269300Y445758D01*
Y452301D01*
X271890Y454891D01*
Y465590D01*
G01X265130Y440070D02*
X264600Y440600D01*
Y445200D01*
X265600Y446200D01*
Y459999D01*
X267171Y461570D01*
Y466372D01*
X267165Y466378D01*
G01X271710Y449840D02*
Y451310D01*
X273537Y453137D01*
Y461300D01*
X274252Y462015D01*
Y465590D01*
G01X277000Y79075D02*
X272580Y83495D01*
X272555D01*
X272505Y83545D01*
G01X281000Y79075D02*
Y80050D01*
X277505Y83545D01*
G01X285000Y79075D02*
Y81200D01*
X282705Y83495D01*
X282555D01*
X282505Y83545D01*
G01X278220Y101530D02*
X279667Y100083D01*
X280784D01*
X283791Y103090D01*
X286549D01*
G01X278394Y111035D02*
X281220Y108209D01*
X286549D01*
G01X271687Y108226D02*
X272926D01*
X274200Y109500D01*
G01X278868Y183883D02*
X282907D01*
G01X289254Y182385D02*
X287670Y183969D01*
X285361D01*
X285275Y183883D01*
X282907D01*
G01X281889Y282077D02*
X282911Y281055D01*
Y279569D01*
G01D02*
X282930Y279550D01*
X281889Y278509D01*
Y275497D01*
G01X285911Y282077D02*
Y279569D01*
G01D02*
Y275497D01*
G01X290417Y383897D02*
X286713D01*
X285516Y385094D01*
X283167D01*
X282667Y385594D01*
Y392057D01*
X285193Y394583D01*
X285472D01*
G01X283973Y382553D02*
X285926Y380600D01*
X293500D01*
X294300Y381400D01*
Y382540D01*
X295657Y383897D01*
X297897D01*
G01X290139Y393332D02*
X288749D01*
X287498Y394583D01*
X285472D01*
G01X280765Y431556D02*
Y426235D01*
X287500Y419500D01*
Y416100D01*
G01X272999Y430500D02*
Y434400D01*
X274500Y435901D01*
X278400D01*
X288765Y446266D01*
Y461674D01*
X288425Y462014D01*
Y466378D01*
G01X280765Y431556D02*
Y434064D01*
X291623Y444922D01*
Y447747D01*
G01X283622Y447155D02*
X280000Y450777D01*
Y459587D01*
X278976Y462061D01*
Y466378D01*
G01X276632Y439502D02*
X278574D01*
X287146Y448074D01*
Y460996D01*
X286063Y462079D01*
Y466378D01*
G01X283674Y449975D02*
X281871Y451778D01*
Y460545D01*
X281339Y461830D01*
Y466378D01*
G01X275138Y451215D02*
Y460408D01*
X276620Y461890D01*
Y466372D01*
X276614Y466378D01*
G01X283715Y452769D02*
X285593Y454647D01*
Y460171D01*
X283701Y462063D01*
Y466378D01*
G01X292572Y160025D02*
X297222Y155375D01*
G02X299138Y153043I-10881J-10893D01*
G01X300752Y150631D01*
X301936Y149447D01*
G01X295410Y169786D02*
X295420D01*
X298320Y166886D01*
G02X298584Y166249I-636J-637D01*
G01Y165292D01*
G03X298716Y164973I451J0D01*
G01X303053Y160636D01*
G03X303128Y160563I2819J2821D01*
G03X304346Y159772I2745J2893D01*
G01X309711Y157548D01*
G02X310083Y157300I-438J-1059D01*
G01X317936Y149447D01*
G01X292572Y160025D02*
X289110Y163487D01*
G01X305936Y149447D02*
X300819Y154564D01*
G01X289254Y172792D02*
X290307Y171739D01*
G02X290632Y171263I-1093J-1095D01*
G02X290717Y170851I-945J-410D01*
G01Y169413D01*
G03X292281Y165637I5340J0D01*
G01X293882Y164036D01*
G02X294271Y163097I-939J-939D01*
G01Y162003D01*
G03X294901Y160482I2151J0D01*
G01X300819Y154564D01*
G01X292260Y169643D02*
X292690Y168476D01*
G03X292904Y168141I868J319D01*
G01X295371Y165674D01*
G02X295636Y165034I-640J-640D01*
G01Y163224D01*
G03X296059Y162203I1444J0D01*
G01X300542Y157720D01*
G03X300604Y157669I290J289D01*
G01X303361Y155827D01*
G02X304452Y154931I-4005J-5988D01*
G01X309936Y149447D01*
G01X309394Y153989D02*
X307257Y156126D01*
G03X305860Y157060I-3047J-3046D01*
G01X305213Y157328D01*
X303837Y157990D01*
X303641Y158072D01*
X302783Y158428D01*
X302518Y158605D01*
X301843Y159244D01*
X301288Y159800D01*
Y159807D01*
X300772Y160297D01*
X297312Y163757D01*
G02X297009Y164489I733J732D01*
G01Y165445D01*
G03X296927Y165934I-1497J0D01*
G03X296704Y166290I-884J-306D01*
G01X294173Y168821D01*
G02X293856Y169586I766J765D01*
G01Y170863D01*
G03X293770Y171305I-1165J3D01*
G03X293251Y172083I-2194J-902D01*
G01X292398Y172936D01*
X292384D01*
G01X311269Y159165D02*
X310521Y159475D01*
G02X310111Y159661I2648J6382D01*
G03X308838Y160139I-3054J-6199D01*
G02X308456Y160259I1088J4133D01*
G02X306650Y161030I7005J18910D01*
G01X305091Y162001D01*
G02X302555Y164015I7508J12058D01*
G01X298374Y168196D01*
G02X297535Y169397I2949J2954D01*
G02X297445Y169808I888J410D01*
G01Y173056D01*
G03X296917Y174331I-1802J0D01*
G01X296749Y174499D01*
G03X295496Y175018I-1253J-1252D01*
G01X294804D01*
G03X294151Y174888I1J-1708D01*
G01X293604Y174662D01*
G02X292907Y174524I-697J1691D01*
G01X291271D01*
G02X290492Y174847I0J1101D01*
G01X289254Y176085D01*
G01X292260Y163487D02*
G02X290995Y163852I0J2375D01*
G01X290019Y164828D01*
G03X289656Y164985I-379J-378D01*
G02X289269Y165152I16J568D01*
G01X288619Y165802D01*
G01D02*
X287908Y166513D01*
Y170320D01*
G01X317834Y161378D02*
X316627Y162585D01*
X316078Y163910D01*
X315477Y164511D01*
G03X314371Y165036I-1289J-1289D01*
G01X314344Y165039D01*
G02X313935Y165140I140J1446D01*
G02X313124Y165476I81849J198705D01*
G02X312775Y165711I420J1000D01*
G01X311407Y167079D01*
G03X308786Y168165I-2621J-2620D01*
G01X308644D01*
X308642Y168167D01*
X307374D01*
X307372Y168165D01*
X304776D01*
G02X304112Y168440I0J939D01*
G01X303395Y169157D01*
G02X303002Y170105I947J948D01*
G01Y173075D01*
G03X301793Y175993I-4126J0D01*
G01X299809Y177977D01*
G03X296772Y179235I-3037J-3037D01*
G01X295410D01*
G01X325855Y159411D02*
X316118D01*
G02X313889Y160334I0J3153D01*
G01X313307Y160916D01*
X312758Y162897D01*
Y163646D01*
G03X312410Y164482I-1182J-1D01*
G03X311740Y164974I-1919J-1911D01*
G03X311302Y165080I-436J-844D01*
G01X307286D01*
G02X305084Y165992I0J3113D01*
G01X301747Y169329D01*
G02X301016Y171094I1764J1765D01*
G01Y172772D01*
G03X300739Y174149I-3561J0D01*
G03X300574Y174394I-709J-300D01*
G01X297556Y177412D01*
G03X297151Y177580I-405J-405D01*
G01X295143D01*
G02X294591Y177809I0J781D01*
G01X293594Y178806D01*
G03X293214Y179065I-867J-864D01*
G03X292386Y179235I-824J-1914D01*
G01X292260D01*
G01X302800Y286200D02*
X299400D01*
X299100Y286500D01*
G01X294162Y369127D02*
X298705D01*
G01X294157Y376023D02*
X298255D01*
X298705Y375573D01*
Y369127D01*
G01X335708Y372008D02*
X330000Y366300D01*
Y364500D01*
X328200Y362700D01*
X312100D01*
X309900Y364900D01*
X304800D01*
X303100Y366600D01*
Y375100D01*
X297897Y380303D01*
Y383897D01*
G01X293289Y393332D02*
X298152D01*
G01X302675Y393352D02*
X302655Y393332D01*
X298152D01*
G01X290139Y397365D02*
Y393332D01*
G01X309935Y108209D02*
X313674D01*
X315383Y106500D01*
X319300D01*
X321800Y109000D01*
G01X309935Y105649D02*
X313850D01*
X316599Y102900D01*
X322500D01*
G01X317000Y111500D02*
X315001D01*
X314269Y110768D01*
X309935D01*
G01X310200Y133325D02*
X310300D01*
X311717Y131908D01*
X312267D01*
X314000Y130175D01*
G01Y133325D02*
X318000D01*
G01X301936Y141497D02*
X302230D01*
X303430Y142697D01*
X303982Y144030D01*
Y146423D01*
X303452Y147703D01*
X301936Y149219D01*
Y149447D01*
G01X305936D02*
Y149207D01*
X307286Y147857D01*
X307982Y146177D01*
Y143839D01*
X307596Y142907D01*
X306186Y141497D01*
X305936D01*
G01X309936Y149447D02*
Y149209D01*
X311271Y147874D01*
X311982Y146157D01*
Y143740D01*
X311605Y142830D01*
X310272Y141497D01*
X309936D01*
G01X313936Y149447D02*
X309394Y153989D01*
G01X313936Y141497D02*
X314236D01*
X315447Y142708D01*
X315982Y144000D01*
Y146194D01*
X315314Y147807D01*
X313936Y149185D01*
Y149447D01*
G01X317834Y165378D02*
X316841Y166371D01*
X314838D01*
X314419Y166578D01*
G02X314077Y166782I1128J2280D01*
G01X313939Y166920D01*
G02X313277Y168518I1598J1598D01*
G01Y169387D01*
G03X311042Y171622I-2235J0D01*
G01X310246D01*
G03X309356Y171453I2J-2440D01*
G02X309126Y171376I-889J2273D01*
G02X308709Y171319I-416J1489D01*
G01X307549D01*
G02X307132Y171370I-2J1713D01*
G02X305829Y172109I685J2726D01*
G01X305002Y172936D01*
G01X317834Y157378D02*
X315810D01*
G02X315371Y157465I-1J1146D01*
G01X311269Y159165D01*
G01X314930Y171289D02*
X323837D01*
X323959Y171411D01*
X325855D01*
G01X317834Y177378D02*
X316488D01*
X316278Y177588D01*
X314930D01*
G01X325855Y175411D02*
X317322D01*
X315960Y175975D01*
X314672D01*
G03X313314Y175479I0J-2107D01*
G02X310598Y174488I-2715J3224D01*
G01D02*
X307347D01*
G02X306046Y175027I0J1840D01*
G01X305002Y176071D01*
Y176085D01*
G01X310866Y179672D02*
X308668Y179235D01*
X308152D01*
G01X321602Y187345D02*
X320381D01*
X318996Y185960D01*
X315851Y184657D01*
X310866Y179672D01*
G01X317834Y173378D02*
X315991D01*
X314930Y174439D01*
G01X305605Y200789D02*
Y202113D01*
X306220Y202728D01*
X312718D01*
X314307Y201139D01*
G01X317116Y199375D02*
X315693D01*
X314307Y197989D01*
G01X316659Y266511D02*
Y255759D01*
X316276Y255376D01*
G01D02*
X315400Y254500D01*
X306000D01*
X304500Y256000D01*
Y267500D01*
X307242Y270242D01*
Y276752D01*
X304308Y279686D01*
X302879D01*
G01Y282487D02*
X304613D01*
X308900Y278200D01*
Y271900D01*
X309900Y270900D01*
X312500D01*
X314100Y272500D01*
Y274089D01*
G01X321800Y60055D02*
X324345Y62600D01*
X334300D01*
X337400Y65700D01*
Y69700D01*
X341740Y74040D01*
Y81847D01*
X347390Y87497D01*
Y269810D01*
X340800Y276400D01*
X321300D01*
X319500Y278200D01*
X313100D01*
X311541Y276641D01*
Y274089D01*
G01X311670Y285160D02*
X307668D01*
G01X308486Y378422D02*
Y373061D01*
X308425Y373000D01*
G01D02*
X307000Y371575D01*
Y367500D01*
G01D02*
X310425D01*
X311925Y369000D01*
G01D02*
Y366475D01*
G01X304746Y386296D02*
X306972D01*
X310431Y389755D01*
Y393352D01*
G01X305825Y397382D02*
Y393352D01*
G01D02*
X310431D01*
G01X326313Y104676D02*
X326557D01*
X328495Y106614D01*
X333890D01*
X334340Y106164D01*
Y104676D01*
G01X322500Y102900D02*
X324537D01*
X326313Y104676D01*
G01Y112707D02*
X326525D01*
X329026Y115208D01*
X333008D01*
X334340Y113876D01*
Y112708D01*
G01X326313Y112707D02*
X318207D01*
X317000Y111500D01*
G01X326313Y108692D02*
X326472D01*
X328436Y110656D01*
X333890D01*
X334340Y110206D01*
Y108692D01*
G01X321800Y109000D02*
X323177D01*
X323485Y108692D01*
X326313D01*
G01X318000Y133325D02*
Y134762D01*
X320132Y136894D01*
X320474D01*
X322530Y138950D01*
G01X317936Y141497D02*
X318138D01*
X319480Y142839D01*
X319957Y143991D01*
Y146231D01*
X319271Y147888D01*
X317936Y149223D01*
Y149447D01*
G01X321600Y142100D02*
X322530Y141170D01*
Y138950D01*
G01X325855Y167411D02*
X320976D01*
X319445Y166777D01*
X318046Y165378D01*
X317834D01*
G01X325855Y163411D02*
X321092D01*
X319462Y162736D01*
X318104Y161378D01*
X317834D01*
G01X317959Y153377D02*
Y157253D01*
X317834Y157378D01*
G01X325855Y155411D02*
Y159411D01*
G01X329005Y183411D02*
X328769D01*
X326920Y181562D01*
X324006D01*
X321985Y179541D01*
X320217D01*
X318054Y177378D01*
X317834D01*
G01X325855Y179411D02*
Y175411D01*
G01Y187411D02*
Y183411D01*
G01D02*
X322005D01*
G01X321602Y187345D02*
Y187502D01*
X324616Y190516D01*
X324960D01*
X325855Y191411D01*
G01X347100Y313700D02*
X348950Y311850D01*
Y86850D01*
X343300Y81200D01*
Y69400D01*
X339900Y66000D01*
G01X334250Y162911D02*
X333133D01*
X331405Y164639D01*
Y164911D01*
G01X334250Y158911D02*
X333250Y159911D01*
X331405D01*
G01X334250Y154911D02*
X331405D01*
G01X334250Y178911D02*
X333250Y179911D01*
X331405D01*
G01X334178Y174911D02*
X331405D01*
G01X334178Y170911D02*
X333178Y169911D01*
X331405D01*
G01X334250Y182926D02*
X331405D01*
G01X334250Y190961D02*
X333200Y189911D01*
X331405D01*
G54D87*
G01X194100Y264255D02*
X194120Y264275D01*
X197850D01*
X197900Y264225D01*
X198000D01*
G01D02*
X198575D01*
X200300Y262500D01*
X201000D01*
G01X209300Y457700D02*
X207343Y459657D01*
Y466378D01*
G01X215000Y458600D02*
Y460000D01*
X214429Y460571D01*
Y466378D01*
G01X222200Y458700D02*
Y459800D01*
X221516Y460484D01*
Y466378D01*
G54D78*
X320000Y396000D03*
Y403000D03*
X327000Y396000D03*
Y403000D03*
G54D69*
X163110Y364169D03*
G54D97*
G01X80098Y465590D02*
Y462603D01*
X80555Y462146D01*
Y460733D01*
X79121Y457273D01*
X61600Y439751D01*
Y432251D01*
X60622Y431273D01*
G01X82461Y465590D02*
Y462662D01*
X82005Y462206D01*
Y460444D01*
X80351Y456451D01*
X63050Y439150D01*
Y432345D01*
X64122Y431273D01*
G01X56482Y456844D02*
X57507Y455819D01*
X58734D01*
X59295Y456380D01*
Y462206D01*
X58839Y462662D01*
Y465590D01*
G01X56482Y453344D02*
X57507Y454369D01*
X59335D01*
X60745Y455779D01*
Y462246D01*
X61201Y462702D01*
Y465590D01*
G01X158189Y359838D02*
Y358837D01*
X158448Y358578D01*
Y357067D01*
X158116Y356267D01*
X155050Y353200D01*
X149721D01*
X146099Y351700D01*
X138901D01*
X130601Y343400D01*
X126599D01*
X115018Y331820D01*
X111354Y322974D01*
Y320346D01*
X111353Y320345D01*
X107910Y315189D01*
Y306762D01*
X97370Y296222D01*
Y291422D01*
X93323Y287375D01*
X91875D01*
X87050Y282550D01*
Y255101D01*
X85050Y253101D01*
Y241801D01*
X76800Y233551D01*
Y221302D01*
X84950Y201620D01*
Y172899D01*
X92200Y165649D01*
Y126222D01*
X97200Y114162D01*
X97201Y109121D01*
X98789Y105289D01*
X101457Y101292D01*
X108000Y94750D01*
X118780D01*
X131093Y99850D01*
X140672D01*
X142343Y99158D01*
X145297Y96204D01*
X147243Y91506D01*
X155099Y83650D01*
X163719D01*
X171769Y91700D01*
Y95203D01*
X172847Y96281D01*
G01X63569Y456844D02*
X64594Y455819D01*
X65469D01*
X66381Y456731D01*
Y462206D01*
X65925Y462662D01*
Y465590D01*
G01X63569Y453344D02*
X64594Y454369D01*
X66070D01*
X67831Y456130D01*
Y462246D01*
X68287Y462702D01*
Y465590D01*
G01X160157Y359838D02*
Y358831D01*
X159898Y358572D01*
Y356778D01*
X159346Y355445D01*
X155651Y351750D01*
X150010D01*
X146388Y350250D01*
X139502D01*
X131202Y341950D01*
X127200D01*
X119742Y334492D01*
Y333374D01*
X118553Y332185D01*
X117435D01*
X116248Y330998D01*
X112804Y322685D01*
Y319905D01*
X109360Y314749D01*
Y306161D01*
X98820Y295621D01*
Y290821D01*
X93924Y285925D01*
X92476D01*
X88500Y281949D01*
Y276570D01*
X89380Y275690D01*
Y274010D01*
X88500Y273130D01*
Y270630D01*
X89380Y269750D01*
Y268070D01*
X88500Y267190D01*
Y265510D01*
X89380Y264630D01*
Y262950D01*
X88500Y262070D01*
Y254500D01*
X86500Y252500D01*
Y241200D01*
X78250Y232950D01*
Y221591D01*
X86400Y201909D01*
Y173500D01*
X93650Y166250D01*
Y126511D01*
X98650Y114451D01*
X98651Y109410D01*
X100074Y105976D01*
X102584Y102217D01*
X108601Y96200D01*
X118491D01*
X130804Y101300D01*
X140961D01*
X143165Y100388D01*
X146527Y97026D01*
X148473Y92328D01*
X150806Y89995D01*
X151937D01*
X153069Y88863D01*
Y87731D01*
X155700Y85100D01*
X157600D01*
X158400Y85900D01*
X160000D01*
X160800Y85100D01*
X163118D01*
X166924Y88906D01*
Y90038D01*
X168056Y91170D01*
X169188D01*
X170319Y92301D01*
Y95309D01*
X169347Y96281D01*
G01X163423D02*
X162369Y95227D01*
Y92050D01*
X160569Y90250D01*
X156999D01*
X152650Y94599D01*
Y98299D01*
X144199Y106750D01*
X128101D01*
X123482Y102131D01*
X119061Y100300D01*
X110239D01*
X104534Y106005D01*
X102987Y108319D01*
X102240Y110122D01*
Y118928D01*
X101015Y121885D01*
X98296Y124605D01*
X97400Y126766D01*
Y132070D01*
X98730Y133400D01*
Y166919D01*
X90050Y175599D01*
Y202599D01*
X82450Y220947D01*
Y226501D01*
X91350Y235401D01*
Y248201D01*
X93700Y250551D01*
Y267250D01*
X106481Y298112D01*
X112930Y304561D01*
Y313684D01*
X122990Y328742D01*
X131949Y337700D01*
X137500D01*
X141000Y341200D01*
X144001D01*
X150901Y348100D01*
X160448D01*
X167150Y354802D01*
Y356199D01*
X166322Y357027D01*
Y358578D01*
X166063Y358837D01*
Y359838D01*
G01X159923Y96281D02*
Y96277D01*
X160919Y95281D01*
Y92651D01*
X159968Y91700D01*
X157600D01*
X154100Y95200D01*
Y98900D01*
X152153Y100847D01*
Y101964D01*
X150964Y103153D01*
X149847D01*
X144800Y108200D01*
X139170D01*
X138380Y108990D01*
X136700D01*
X135910Y108200D01*
X127500D01*
X126003Y106703D01*
X124886D01*
X123697Y105514D01*
Y104398D01*
X122660Y103361D01*
X118772Y101750D01*
X110840D01*
X105661Y106930D01*
X104271Y109009D01*
X103982Y109707D01*
X103981Y109708D01*
X103690Y110411D01*
Y119217D01*
X102245Y122707D01*
X99525Y125427D01*
X98850Y127055D01*
Y131469D01*
X100180Y132799D01*
Y156200D01*
X100970Y156990D01*
Y158670D01*
X100180Y159460D01*
Y161140D01*
X100970Y161930D01*
Y163610D01*
X100180Y164400D01*
Y167520D01*
X91500Y176200D01*
Y202888D01*
X86074Y215987D01*
X86491Y216993D01*
X85848Y218547D01*
X84841Y218963D01*
X83900Y221236D01*
Y225900D01*
X87511Y229511D01*
X88600D01*
X89789Y230700D01*
Y231789D01*
X92800Y234800D01*
Y247600D01*
X95150Y249950D01*
Y266961D01*
X107711Y297290D01*
X114380Y303960D01*
Y313244D01*
X124117Y327817D01*
X132550Y336250D01*
X138101D01*
X141601Y339750D01*
X144602D01*
X151502Y346650D01*
X161049D01*
X168600Y354201D01*
Y356800D01*
X167772Y357628D01*
Y358572D01*
X168031Y358831D01*
Y359838D01*
G01X164094Y368500D02*
Y369394D01*
X164354Y369654D01*
Y378294D01*
X160100Y382548D01*
Y386284D01*
X159050Y387334D01*
G01X166063Y368500D02*
Y369337D01*
X165804Y369596D01*
Y378895D01*
X161550Y383149D01*
Y386334D01*
X162550Y387334D01*
G01X178500Y379625D02*
X179800Y378325D01*
Y376352D01*
X176292Y372844D01*
X169700D01*
X168291Y371435D01*
Y369792D01*
X168031Y369532D01*
Y368500D01*
G01X182500Y379625D02*
X181250Y378375D01*
Y375751D01*
X176893Y371394D01*
X170301D01*
X169741Y370834D01*
Y369760D01*
X170000Y369501D01*
Y368500D01*
G01X178500Y382775D02*
X178876D01*
X179900Y383799D01*
Y384584D01*
X178850Y385634D01*
G01X182500Y382775D02*
X182125D01*
X181350Y383550D01*
Y384634D01*
X182350Y385634D01*
G01X202618Y465590D02*
Y462782D01*
X203074Y462326D01*
Y458946D01*
X207400Y448500D01*
Y425245D01*
X211100Y416312D01*
Y408148D01*
X215710Y403538D01*
X261640D01*
X273027Y398821D01*
X274137Y397711D01*
X277371Y389904D01*
Y383419D01*
X278070Y381731D01*
Y374380D01*
X283350Y361632D01*
Y340500D01*
X278850Y336000D01*
Y313205D01*
X262295Y273248D01*
X261513Y272466D01*
X254433Y269534D01*
X251933Y267034D01*
X250442Y264803D01*
X243800Y248774D01*
Y246984D01*
X242430Y245614D01*
G01X204980Y465590D02*
Y462680D01*
X204524Y462224D01*
Y459235D01*
X208850Y448789D01*
Y425534D01*
X212550Y416601D01*
Y408749D01*
X216311Y404988D01*
X261929D01*
X273849Y400051D01*
X275367Y398533D01*
X278821Y390193D01*
Y383708D01*
X279520Y382020D01*
Y374669D01*
X284800Y361921D01*
Y339899D01*
X280300Y335399D01*
Y312916D01*
X263525Y272426D01*
X262335Y271236D01*
X258529Y269660D01*
X255255Y268304D01*
X253060Y266109D01*
X251727Y264116D01*
X245250Y248485D01*
Y246794D01*
X246430Y245614D01*
G01X213225Y442220D02*
X214250Y443245D01*
Y452150D01*
X211600Y454800D01*
Y458548D01*
X210161Y459987D01*
Y462238D01*
X209705Y462694D01*
Y465590D01*
G01X216725Y442220D02*
X215700Y443245D01*
Y452751D01*
X213050Y455401D01*
Y459149D01*
X211611Y460588D01*
Y462310D01*
X212067Y462766D01*
Y465590D01*
G01X217725Y410150D02*
X218800Y411225D01*
Y413752D01*
X221750Y416702D01*
Y430150D01*
X219865Y432035D01*
Y454235D01*
X217248Y456852D01*
Y462252D01*
X216791Y462709D01*
Y465590D01*
G01X221225Y410150D02*
X220250Y411125D01*
Y413151D01*
X223200Y416101D01*
Y430751D01*
X221315Y432636D01*
Y454836D01*
X218698Y457453D01*
Y462198D01*
X219154Y462654D01*
Y465590D01*
G01X242430Y242464D02*
X243700Y241194D01*
Y239748D01*
X244835Y238612D01*
X245600Y236766D01*
Y234699D01*
X245300Y234399D01*
Y233001D01*
X244450Y232151D01*
G01X246430Y242464D02*
X245150Y241184D01*
Y240349D01*
X246065Y239434D01*
X247050Y237055D01*
Y234098D01*
X246750Y233798D01*
Y233000D01*
X247599Y232151D01*
G01X397766Y210938D02*
Y210318D01*
X398025Y210059D01*
Y196442D01*
X398645Y192932D01*
X397737Y191636D01*
X385588Y189494D01*
X383990Y187214D01*
X384848Y182352D01*
X387129Y180755D01*
X410032Y184793D01*
X411329Y183884D01*
X411978Y180209D01*
X411070Y178913D01*
X385439Y174394D01*
X383841Y172114D01*
X384699Y167253D01*
X386980Y165655D01*
X410154Y169741D01*
X411451Y168832D01*
X412100Y165157D01*
X411192Y163861D01*
X385258Y159288D01*
X383660Y157010D01*
X384518Y152148D01*
X386799Y150550D01*
X409899Y154623D01*
X411196Y153714D01*
X411845Y150039D01*
X410937Y148743D01*
X385724Y144297D01*
X384126Y142019D01*
X384984Y137156D01*
X387265Y135559D01*
X410263Y139614D01*
X411560Y138705D01*
X412209Y135029D01*
X411301Y133731D01*
X385590Y129201D01*
X383992Y126920D01*
X384850Y122058D01*
X387131Y120461D01*
X410016Y124496D01*
X411313Y123587D01*
X411962Y119912D01*
X411054Y118616D01*
X385145Y114048D01*
X383548Y111769D01*
X384406Y106907D01*
X386687Y105310D01*
X410270Y109468D01*
X411567Y108559D01*
X412216Y104884D01*
X411308Y103588D01*
X385399Y99020D01*
X383801Y96740D01*
X384659Y91878D01*
X386940Y90281D01*
X410183Y94379D01*
X411480Y93470D01*
X412129Y89795D01*
X411221Y88499D01*
X390411Y84830D01*
X388813Y82550D01*
X389671Y77688D01*
X391952Y76091D01*
X409421Y79171D01*
X410718Y78262D01*
X411367Y74587D01*
X410459Y73291D01*
X390263Y69730D01*
X388665Y67450D01*
X389523Y62588D01*
X391804Y60991D01*
X409144Y64049D01*
X410441Y63140D01*
X411090Y59465D01*
X410182Y58169D01*
X390414Y54683D01*
X388816Y52403D01*
X389674Y47541D01*
X391955Y45944D01*
X409018Y48953D01*
X410315Y48044D01*
X410964Y44369D01*
X410056Y43073D01*
X391031Y39718D01*
X389433Y37438D01*
X390290Y32576D01*
X392572Y30979D01*
X408836Y33846D01*
X410133Y32937D01*
X410782Y29262D01*
X409874Y27966D01*
X390370Y24528D01*
X388773Y22249D01*
X389630Y17387D01*
X391912Y15790D01*
X410298Y19032D01*
X411595Y18123D01*
X412244Y14447D01*
X411336Y13149D01*
X390361Y9453D01*
X388763Y7173D01*
X389620Y2311D01*
X391902Y714D01*
X410255Y3950D01*
X411552Y3041D01*
X412201Y-634D01*
X411293Y-1930D01*
X390385Y-5616D01*
X388787Y-7896D01*
X389644Y-12758D01*
X391926Y-14355D01*
X410402Y-11097D01*
X411699Y-12006D01*
X412348Y-15681D01*
X411440Y-16978D01*
X390281Y-20709D01*
X388683Y-22988D01*
X388787Y-23580D01*
X388788D01*
X389540Y-27850D01*
X391822Y-29447D01*
X409678Y-26299D01*
X410975Y-27208D01*
X411624Y-30883D01*
X410716Y-32179D01*
X390422Y-35757D01*
X388825Y-38036D01*
X389683Y-42898D01*
X391965Y-44495D01*
X405486Y-42111D01*
X406783Y-43020D01*
X407432Y-46695D01*
X406524Y-47991D01*
X400474Y-49058D01*
X398025Y-51507D01*
Y-66743D01*
X397766Y-67002D01*
Y-67622D01*
G01X399734Y210938D02*
Y210318D01*
X399475Y210059D01*
Y196570D01*
X400178Y192592D01*
X398580Y190312D01*
X386431Y188170D01*
X385523Y186874D01*
X386172Y183196D01*
X387469Y182288D01*
X410372Y186326D01*
X412653Y184727D01*
X413511Y179869D01*
X411913Y177589D01*
X386282Y173070D01*
X385374Y171774D01*
X386023Y168096D01*
X387320Y167188D01*
X410494Y171274D01*
X412775Y169675D01*
X413633Y164817D01*
X412035Y162537D01*
X386101Y157964D01*
X385193Y156669D01*
X385842Y152991D01*
X387139Y152083D01*
X410239Y156156D01*
X412520Y154557D01*
X413378Y149699D01*
X411780Y147419D01*
X386567Y142973D01*
X385659Y141678D01*
X386308Y138000D01*
X387605Y137092D01*
X410603Y141147D01*
X412884Y139548D01*
X413742Y134690D01*
X412145Y132407D01*
X386433Y127877D01*
X385525Y126580D01*
X386174Y122902D01*
X387471Y121994D01*
X410356Y126029D01*
X412637Y124430D01*
X413495Y119572D01*
X411897Y117292D01*
X385988Y112724D01*
X385081Y111429D01*
X385730Y107751D01*
X387027Y106843D01*
X410610Y111001D01*
X412891Y109402D01*
X413749Y104544D01*
X412151Y102264D01*
X386242Y97696D01*
X385334Y96400D01*
X385983Y92722D01*
X387280Y91814D01*
X410523Y95912D01*
X412804Y94313D01*
X413662Y89455D01*
X412064Y87175D01*
X391254Y83506D01*
X390346Y82210D01*
X390995Y78532D01*
X392292Y77624D01*
X409761Y80704D01*
X412042Y79105D01*
X412900Y74247D01*
X411302Y71967D01*
X391106Y68406D01*
X390198Y67110D01*
X390847Y63432D01*
X392144Y62524D01*
X409484Y65582D01*
X411765Y63983D01*
X412623Y59125D01*
X411025Y56845D01*
X391257Y53359D01*
X390349Y52063D01*
X390998Y48385D01*
X392295Y47477D01*
X409358Y50486D01*
X411639Y48887D01*
X412497Y44029D01*
X410899Y41749D01*
X391874Y38394D01*
X390966Y37098D01*
X391615Y33420D01*
X392912Y32512D01*
X409176Y35379D01*
X411457Y33781D01*
X412315Y28922D01*
X410717Y26642D01*
X391213Y23204D01*
X390306Y21909D01*
X390955Y18231D01*
X392252Y17323D01*
X410638Y20565D01*
X412919Y18966D01*
X413777Y14108D01*
X412180Y11825D01*
X391204Y8129D01*
X390296Y6833D01*
X390945Y3155D01*
X392242Y2247D01*
X410595Y5483D01*
X412876Y3884D01*
X413734Y-974D01*
X412136Y-3254D01*
X391228Y-6940D01*
X390320Y-8236D01*
X390969Y-11914D01*
X392266Y-12822D01*
X410742Y-9564D01*
X413023Y-11163D01*
X413881Y-16021D01*
X412284Y-18303D01*
X391124Y-22033D01*
X390216Y-23328D01*
X390865Y-27006D01*
X392162Y-27914D01*
X410018Y-24766D01*
X412299Y-26365D01*
X413157Y-31223D01*
X411559Y-33503D01*
X391265Y-37081D01*
X390358Y-38376D01*
X391007Y-42054D01*
X392305Y-42962D01*
X405826Y-40578D01*
X408107Y-42177D01*
X408965Y-47035D01*
X407367Y-49315D01*
X401176Y-50407D01*
X399475Y-52108D01*
Y-66743D01*
X399734Y-67002D01*
Y-67622D01*
G01X407766Y261650D02*
Y262270D01*
X408025Y262529D01*
Y279108D01*
X410037Y281980D01*
X424223Y284484D01*
X425131Y285779D01*
X424482Y289455D01*
X423186Y290364D01*
X398895Y286079D01*
X396613Y287676D01*
X395755Y292538D01*
X397353Y294817D01*
X424302Y299571D01*
X425210Y300867D01*
X424561Y304543D01*
X423265Y305451D01*
X398936Y301160D01*
X396654Y302757D01*
X395796Y307619D01*
X397393Y309898D01*
X424257Y314637D01*
X425165Y315933D01*
X424516Y319609D01*
X423220Y320517D01*
X398715Y316195D01*
X396433Y317792D01*
X395575Y322655D01*
X397173Y324933D01*
X423205Y329525D01*
X424113Y330820D01*
X423464Y334496D01*
X422167Y335404D01*
X398341Y331202D01*
X396059Y332800D01*
X395201Y337661D01*
X396799Y339941D01*
X420225Y344073D01*
X421133Y345369D01*
X420484Y349045D01*
X419188Y349953D01*
X398038Y346222D01*
X395755Y347820D01*
X394897Y352681D01*
X396495Y354960D01*
X420503Y359196D01*
X421411Y360492D01*
X420762Y364168D01*
X419466Y365076D01*
X397393Y361182D01*
X395111Y362780D01*
X394253Y367641D01*
X395851Y369920D01*
X420650Y374295D01*
X421558Y375592D01*
X420909Y379268D01*
X419614Y380176D01*
X403112Y377265D01*
X400830Y378863D01*
X399972Y383724D01*
X401570Y386004D01*
X408137Y387162D01*
X409045Y388458D01*
X408025Y394239D01*
Y408331D01*
X407766Y408590D01*
Y409210D01*
G01X409734Y261650D02*
Y262270D01*
X409475Y262529D01*
Y278650D01*
X410880Y280656D01*
X425066Y283160D01*
X426664Y285439D01*
X425806Y290298D01*
X423527Y291897D01*
X399235Y287612D01*
X397937Y288520D01*
X397288Y292198D01*
X398196Y293493D01*
X425145Y298247D01*
X426743Y300527D01*
X425885Y305386D01*
X423605Y306984D01*
X399276Y302693D01*
X397978Y303601D01*
X397329Y307279D01*
X398236Y308574D01*
X425100Y313313D01*
X426698Y315593D01*
X425840Y320452D01*
X423560Y322050D01*
X399055Y317728D01*
X397757Y318636D01*
X397108Y322314D01*
X398016Y323609D01*
X424048Y328201D01*
X425646Y330480D01*
X424788Y335339D01*
X422507Y336937D01*
X398681Y332735D01*
X397383Y333644D01*
X396734Y337321D01*
X397642Y338617D01*
X421068Y342749D01*
X422666Y345029D01*
X421808Y349888D01*
X419528Y351486D01*
X398378Y347755D01*
X397079Y348664D01*
X396430Y352341D01*
X397338Y353636D01*
X421346Y357872D01*
X422944Y360152D01*
X422086Y365011D01*
X419806Y366609D01*
X397733Y362715D01*
X396435Y363624D01*
X395786Y367301D01*
X396694Y368596D01*
X421494Y372971D01*
X423091Y375252D01*
X422233Y380111D01*
X419954Y381709D01*
X403452Y378798D01*
X402154Y379707D01*
X401505Y383384D01*
X402413Y384680D01*
X408980Y385838D01*
X410578Y388118D01*
X409475Y394366D01*
Y408331D01*
X409734Y408590D01*
Y409210D01*
G01X441000Y96000D02*
X444715D01*
X445275Y95440D01*
Y88455D01*
X444155Y87335D01*
X420799D01*
X418830Y85366D01*
Y81344D01*
X420799Y79375D01*
X470230D01*
X471350Y78255D01*
Y75435D01*
X470230Y74315D01*
X420799D01*
X418830Y72346D01*
Y68324D01*
X420799Y66355D01*
X470600D01*
X471720Y65235D01*
Y62415D01*
X470600Y61295D01*
X420799D01*
X418830Y59326D01*
Y55304D01*
X420799Y53335D01*
X470600D01*
X471720Y52215D01*
Y49395D01*
X470600Y48275D01*
X420799D01*
X418830Y46306D01*
Y42284D01*
X420799Y40315D01*
X470600D01*
X471720Y39195D01*
Y36375D01*
X470600Y35255D01*
X420799D01*
X418830Y33286D01*
Y29264D01*
X420799Y27295D01*
X470600D01*
X471720Y26175D01*
Y23355D01*
X470600Y22235D01*
X447244D01*
X445275Y20266D01*
Y12560D01*
X444715Y12000D01*
X441000D01*
G01X451000Y96000D02*
X447285D01*
X446725Y95440D01*
Y87854D01*
X444756Y85885D01*
X421400D01*
X420280Y84765D01*
Y81945D01*
X421400Y80825D01*
X470831D01*
X472800Y78856D01*
Y74834D01*
X470831Y72865D01*
X421400D01*
X420280Y71745D01*
Y68925D01*
X421400Y67805D01*
X471201D01*
X473170Y65836D01*
Y61814D01*
X471201Y59845D01*
X421400D01*
X420280Y58725D01*
Y55905D01*
X421400Y54785D01*
X471201D01*
X473170Y52816D01*
Y48794D01*
X471201Y46825D01*
X421400D01*
X420280Y45705D01*
Y42885D01*
X421400Y41765D01*
X471201D01*
X473170Y39796D01*
Y35774D01*
X471201Y33805D01*
X421400D01*
X420280Y32685D01*
Y29865D01*
X421400Y28745D01*
X471201D01*
X473170Y26776D01*
Y22754D01*
X471201Y20785D01*
X447845D01*
X446725Y19665D01*
Y12560D01*
X447285Y12000D01*
X451000D01*
G54D88*
G01X65801Y253145D02*
X63061D01*
X61661Y251745D01*
Y247701D01*
G01X69500Y239075D02*
X70900Y240475D01*
Y241500D01*
G01X69339Y247701D02*
Y244840D01*
X67527Y243028D01*
Y241048D01*
X69500Y239075D01*
G01X69339Y265299D02*
Y268340D01*
X71356Y270357D01*
Y271957D01*
X73924Y274525D01*
X74300D01*
G01X77900Y274700D02*
X77725Y274525D01*
X74300D01*
G01X71906Y387332D02*
X71499Y386925D01*
X69000D01*
G01X122000Y269437D02*
Y271249D01*
X122425Y271674D01*
Y277000D01*
G01X134075D02*
X134720Y276355D01*
Y271520D01*
X134500Y271300D01*
Y269437D01*
G01X161296Y409362D02*
X155562D01*
X154200Y408000D01*
G01X139587Y466378D02*
X139593Y466372D01*
Y458343D01*
X138500Y457250D01*
G01X197463Y168913D02*
X194378D01*
X194094Y169197D01*
G01X184806Y194343D02*
Y193949D01*
G01D02*
X187596Y191159D01*
Y190410D01*
G01X206672Y212459D02*
X206293D01*
X203938Y210104D01*
X203542D01*
G01X228712Y196645D02*
X227814Y197543D01*
X225552D01*
G01X222190Y189004D02*
X224643D01*
X225552Y188095D01*
G01X222769Y210143D02*
Y212887D01*
X222402Y213254D01*
G01X222635Y204555D02*
Y206722D01*
X222402Y206955D01*
G01X223015Y200555D02*
Y202077D01*
X222635Y202457D01*
Y204555D01*
G01X229633Y207040D02*
X222487D01*
X222402Y206955D01*
G01X225785Y204555D02*
X227952D01*
X228702Y203805D01*
G01X225919Y210143D02*
X228663D01*
X228702Y210104D01*
G01X228520Y188938D02*
Y191062D01*
X228702Y191244D01*
G01X239884Y194151D02*
X239204Y195783D01*
X239246Y195884D01*
X238337Y198078D01*
G01X232713Y198085D02*
Y194317D01*
X232879Y194151D01*
G01D02*
Y192272D01*
X231851Y191244D01*
G01X237257Y205261D02*
X236695D01*
X235001Y206955D01*
G01X238337Y198078D02*
X236048Y199608D01*
X235001Y200655D01*
G01X239064Y209187D02*
Y207984D01*
X240407Y206641D01*
Y205261D01*
G01D02*
X241863Y203805D01*
X244450D01*
G01X232783Y207040D02*
Y206023D01*
X235001Y203805D01*
G01X232713Y201235D02*
Y202943D01*
X231851Y203805D01*
G01X235064Y212662D02*
Y210167D01*
X235001Y210104D01*
G01X231021Y212662D02*
Y210934D01*
X231851Y210104D01*
G01X243034Y194151D02*
Y192660D01*
X244450Y191244D01*
G01X278868Y187033D02*
X282762Y190927D01*
X284742D01*
X285482Y190187D01*
G01D02*
X285589D01*
X287862Y187914D01*
G54D79*
X372604Y-455313D03*
Y-430313D03*
X372664Y-223791D03*
Y-198791D03*
X372576Y-177041D03*
Y-152041D03*
X372664Y4481D03*
Y29481D03*
X372604Y51231D03*
Y76231D03*
X372664Y373753D03*
Y398753D03*
X393692Y-481375D03*
X382604Y-455313D03*
X393692Y-456375D03*
X382604Y-430313D03*
X382664Y-223791D03*
Y-198791D03*
X382576Y-177041D03*
Y-152041D03*
X393780Y-128853D03*
Y-103853D03*
X393750Y-82222D03*
Y-57222D03*
X382664Y4481D03*
Y29481D03*
X382604Y51231D03*
Y76231D03*
X393750Y200538D03*
Y225538D03*
Y247050D03*
Y272050D03*
X382664Y373753D03*
X393750Y398810D03*
X382664Y398753D03*
X393750Y423810D03*
X403692Y-481375D03*
Y-456375D03*
X403780Y-128853D03*
Y-103853D03*
X403750Y-82222D03*
D03*
Y-57222D03*
D03*
Y200538D03*
D03*
Y225538D03*
D03*
Y247050D03*
D03*
Y272050D03*
D03*
Y398810D03*
D03*
Y423810D03*
D03*
X413750Y-82222D03*
Y-57222D03*
Y200538D03*
Y225538D03*
Y247050D03*
Y272050D03*
Y398810D03*
Y423810D03*
G54D89*
G01X17025Y105500D02*
X12900D01*
G01X40600Y203000D02*
X37815D01*
X22235Y187420D01*
X19100D01*
G01X53441Y91260D02*
Y93726D01*
X49592Y97575D01*
X48000D01*
G01X45276Y98488D02*
X47087D01*
X48000Y97575D01*
G01X35140Y109200D02*
X38300D01*
G01X44500Y212425D02*
X44629Y212554D01*
X47387D01*
X47714Y212227D01*
G01X48059Y214825D02*
X48603D01*
X50103Y213325D01*
Y211203D01*
X41900Y203000D01*
X40600D01*
G01X51500Y258200D02*
X51000Y258700D01*
Y297776D01*
X47440Y301336D01*
G01X59500Y78925D02*
X60000Y78425D01*
Y75500D01*
G01X59500Y73075D02*
X60000Y73575D01*
Y75500D01*
G01X53267Y109094D02*
X57481D01*
X60000Y106575D01*
G01X56600Y320500D02*
X56920Y320820D01*
X63220D01*
X65351Y322951D01*
Y326674D01*
X64100Y327925D01*
G01X50075Y376000D02*
X52000D01*
X52600Y376600D01*
G01D02*
X53100Y377100D01*
X55825D01*
X56625Y376300D01*
G01X56476Y466378D02*
Y460100D01*
G01X76500Y68925D02*
Y66500D01*
G01X68925Y76500D02*
X65928D01*
G01X69500Y235925D02*
X72000D01*
G01X76284Y280470D02*
Y279484D01*
X74475Y277675D01*
X74300D01*
G01X72700Y301200D02*
X71900Y302000D01*
Y306925D01*
G01X72700Y301200D02*
Y298601D01*
X74601Y296700D01*
X75725D01*
G01X77761Y301897D02*
X75725Y299861D01*
Y296700D01*
G01X77736Y466378D02*
Y460336D01*
X77500Y460100D01*
G01X70650Y466378D02*
Y460100D01*
G01X63563Y466378D02*
Y460100D01*
G01X86500Y75000D02*
X90425D01*
X90500Y75075D01*
G01Y397600D02*
Y399925D01*
X94500D01*
G01X82500D02*
Y397600D01*
G01X92809Y417755D02*
Y414971D01*
X95280Y412500D01*
G01X84823Y466378D02*
Y460100D01*
G01X95400Y66500D02*
Y68525D01*
X94500Y69425D01*
G01X98100Y412400D02*
Y414400D01*
X96814Y415686D01*
Y417755D01*
G01X135475Y84300D02*
Y93425D01*
X134300Y94600D01*
X129900D01*
X121705Y91205D01*
X119700Y89200D01*
G01X113325Y109300D02*
Y110925D01*
X116200Y113800D01*
Y115100D01*
G01X115600Y121100D02*
X111600D01*
G01D02*
Y121250D01*
X112000Y121650D01*
Y123500D01*
G01X112500Y125925D02*
Y124000D01*
X112000Y123500D01*
G01X123500Y124925D02*
X122051D01*
X120626Y123500D01*
G01X120250Y164625D02*
X124500D01*
G01X124225Y238300D02*
X119100D01*
X118300Y237500D01*
G01X122000Y261563D02*
Y265050D01*
X121720Y265330D01*
G01X115000Y369500D02*
Y372500D01*
X118025Y375525D01*
Y376800D01*
G01X119575Y397000D02*
Y400675D01*
X120900Y402000D01*
G01X124287Y406262D02*
X123362D01*
X120900Y403800D01*
Y402000D01*
G01X143000Y17310D02*
X132134Y28176D01*
Y51434D01*
X137500Y56800D01*
Y63875D01*
X136000Y65375D01*
Y74700D01*
X137145Y75845D01*
Y82630D01*
X135475Y84300D01*
G01X125500Y121075D02*
X126925Y122500D01*
X129328D01*
G01X129500Y119575D02*
Y122328D01*
X129328Y122500D01*
G01X129928Y139132D02*
Y134672D01*
X131700Y132900D01*
Y131000D01*
G01X124500Y164625D02*
Y167100D01*
G01X124225Y238300D02*
Y234800D01*
G01X125575Y277000D02*
X130925D01*
G01X131216Y280187D02*
X131235Y280168D01*
Y277310D01*
X130925Y277000D01*
G01X130575Y357500D02*
Y353500D01*
G01Y357500D02*
X131700D01*
X133100Y358900D01*
G01X134090Y387024D02*
X133640Y387474D01*
Y390524D01*
G01X139700Y415100D02*
X139500D01*
X138000Y416600D01*
Y417175D01*
G01X163400Y15775D02*
X144535D01*
X143000Y17310D01*
G01X147947Y12657D02*
Y9800D01*
G01X142875Y78700D02*
X146500D01*
X146800Y79000D01*
G01X148400Y155765D02*
X152835D01*
X155323Y153277D01*
X156525D01*
G01X163690Y268610D02*
X160104D01*
X159294Y267800D01*
X154701D01*
X152000Y265099D01*
Y263075D01*
G01X151320Y322700D02*
Y323846D01*
X153602Y326128D01*
G01X148050Y364775D02*
X144225D01*
X140700Y368300D01*
Y370252D01*
G01X145675Y397500D02*
X144400D01*
X143300Y396400D01*
G01X145675Y401750D02*
X143570D01*
X141520Y399700D01*
G01X146600Y410600D02*
X145675Y409675D01*
Y408000D01*
G01X149600Y410500D02*
X148825Y409725D01*
Y408000D01*
G01X153800Y417225D02*
X150050D01*
X150000Y417175D01*
G01Y414750D02*
Y417175D01*
G01D02*
X146000D01*
G01X165700Y11100D02*
X166100Y11500D01*
X167290D01*
X168447Y12657D01*
G01X166733Y119751D02*
Y109567D01*
X173300Y103000D01*
X178724D01*
X181960Y99764D01*
Y99260D01*
G01X155633Y185582D02*
Y181576D01*
X155630Y181573D01*
G01X163646Y185952D02*
X163509Y185815D01*
X161237D01*
G01X168855Y212033D02*
Y211604D01*
X167045Y209794D01*
X166361D01*
G01X156467Y206219D02*
Y203500D01*
G01X160409Y206305D02*
X156553D01*
X156467Y206219D01*
G01X166525Y228400D02*
X166308Y228183D01*
Y225189D01*
G01D02*
X162467D01*
X161278Y224000D01*
X159700D01*
X159464Y223764D01*
X159164D01*
G01X164801Y257386D02*
X160767D01*
X160765Y257388D01*
G01X165013Y249436D02*
X160973D01*
G01D02*
X156963D01*
G01X160765Y257388D02*
X156707D01*
X156695Y257400D01*
G01X169520Y252810D02*
X166146Y249436D01*
X165013D01*
G01X169934Y257258D02*
X169806Y257386D01*
X164801D01*
G01X166895Y291162D02*
X167450Y290607D01*
Y281939D01*
X167359Y281848D01*
G01X159510Y312500D02*
X159896D01*
X161996Y310400D01*
X162800D01*
X164300Y308900D01*
Y296925D01*
X166605Y294620D01*
X169880D01*
X171400Y293100D01*
Y282739D01*
X170509Y281848D01*
G01X181050Y332250D02*
X181000Y332200D01*
X177394D01*
X168994Y323800D01*
X163600D01*
X159100Y319300D01*
Y312910D01*
X159510Y312500D01*
G01X153602Y326128D02*
Y330164D01*
G01X157600Y417225D02*
X155125Y414750D01*
X154000D01*
G01X163700Y422119D02*
Y420223D01*
X169163Y414760D01*
G01X160846Y465590D02*
Y460124D01*
X160852Y460118D01*
G01X178355Y87450D02*
X175150D01*
X169000Y81300D01*
Y78075D01*
G01X182925Y84300D02*
Y85500D01*
X180975Y87450D01*
X178355D01*
G01X170738Y119751D02*
X174741D01*
G01X178761D02*
Y118655D01*
X179500Y117916D01*
Y116800D01*
G01X174741Y119751D02*
X178761D01*
G01X184645Y210104D02*
X184597Y210056D01*
X181541D01*
G01Y213206D02*
X178394D01*
X178346Y213254D01*
G01X181300Y245575D02*
X181315Y245590D01*
X184890D01*
G01X173992Y257256D02*
X173990Y257258D01*
X169934D01*
G01X174400Y254736D02*
Y256848D01*
X173992Y257256D01*
G01X169520Y252810D02*
X171446Y254736D01*
X174400D01*
G01X186830Y287221D02*
X175717D01*
X175713Y287225D01*
G01X175013Y281583D02*
Y286525D01*
X175713Y287225D01*
G01X172977Y277000D02*
Y277251D01*
X175013Y279287D01*
Y281583D01*
G01X172800Y346825D02*
X170700D01*
X169200Y348325D01*
Y349400D01*
G01X178000Y341900D02*
X177880Y342020D01*
X171894D01*
X171098Y341224D01*
G01X181400Y365875D02*
X177500D01*
G01X180350Y368650D02*
X181400Y367600D01*
Y365875D01*
G01X184296Y391448D02*
X181352D01*
X177400Y395400D01*
X174050D01*
X172550Y396900D01*
Y398690D01*
G01X182600Y414875D02*
X185699D01*
X185875Y415051D01*
G01X182600Y418025D02*
X182125Y418500D01*
X177037D01*
G01X185245Y417500D02*
X183125D01*
X182600Y418025D01*
G01X172530Y429470D02*
X170900Y427840D01*
Y423977D01*
X169163Y422240D01*
G01X194830Y83135D02*
X192689D01*
X191312Y84512D01*
G01X188980Y96535D02*
X190200Y97755D01*
Y100500D01*
G01X191434Y119912D02*
X190800Y119278D01*
Y117200D01*
G01X187431Y119912D02*
X191434D01*
G01X195500Y119925D02*
X193096Y117521D01*
Y115600D01*
G01X197463Y172063D02*
X197001Y171601D01*
G01D02*
X193550D01*
G01X194485Y238613D02*
X195091D01*
X196827Y240349D01*
G01X194485Y235463D02*
X197081D01*
X197243Y235301D01*
G01X184890Y245590D02*
Y248929D01*
X185897Y249936D01*
G01X198000Y261075D02*
Y255190D01*
X196240Y253430D01*
G01X194729Y246128D02*
X190693D01*
G01X200460Y253335D02*
X199964D01*
X194729Y248100D01*
Y246128D01*
G01X194100Y261105D02*
X193824Y261381D01*
X191601D01*
X191583Y261363D01*
G01X189980Y287221D02*
Y283155D01*
G01D02*
Y281407D01*
X189228Y280655D01*
G01X186830Y283155D02*
Y287221D01*
G01X189980D02*
Y291140D01*
X189948Y291172D01*
G01X193800Y345325D02*
X192900Y344425D01*
Y343201D01*
X191178Y341479D01*
Y338678D01*
X190600Y338100D01*
Y337900D01*
G01X190922Y350990D02*
X189135D01*
X187220Y349075D01*
G01X200175Y359750D02*
X197030D01*
X196050Y358770D01*
G01X200274Y410960D02*
X199564Y410250D01*
X197625D01*
G01X185075Y422800D02*
Y424490D01*
X189762Y429177D01*
G01X203600Y117000D02*
X204000Y117400D01*
Y119925D01*
G01X199500D02*
Y117940D01*
X199940Y117500D01*
G01X207800Y119925D02*
X211350D01*
X211370Y119945D01*
G01D02*
Y117000D01*
G01X211567Y172289D02*
Y170621D01*
X212991Y169197D01*
G01X206396Y216270D02*
Y215183D01*
X206672Y214907D01*
Y212459D01*
G01X212991Y219553D02*
X210756D01*
X210333Y219130D01*
Y218630D01*
G01Y215480D02*
Y213745D01*
X209842Y213254D01*
G01X206238Y235174D02*
Y234847D01*
X203542Y232151D01*
G01X206238Y238324D02*
X205664D01*
X204163Y236823D01*
Y235922D01*
X203542Y235301D01*
G01X202990Y245087D02*
X198990D01*
G01D02*
Y247811D01*
G01X200460Y253335D02*
X203960D01*
X203800Y253495D01*
Y255799D01*
X204505Y257505D01*
X205300Y258300D01*
X205500D01*
G01X211265Y267300D02*
X211352D01*
X211640Y267588D01*
X213762D01*
X213833Y267517D01*
G01X208500Y258825D02*
X214050D01*
X214100Y258775D01*
G01X205500Y258300D02*
X206201Y259001D01*
X208324D01*
X208500Y258825D01*
G01X204179Y305847D02*
X202830D01*
X201330Y304347D01*
Y301145D01*
X202075Y300400D01*
G01X210600Y308275D02*
X213085D01*
X213610Y308800D01*
G01X210600Y305125D02*
X207776D01*
X207054Y305847D01*
X204179D01*
G01X214400Y303997D02*
X211728D01*
X210600Y305125D01*
G01X216877Y372129D02*
X215698Y370950D01*
X214339D01*
X212839Y369450D01*
Y367852D01*
X213386Y367305D01*
X215420D01*
G01X200000Y455800D02*
Y461200D01*
X200256Y461456D01*
Y466378D01*
G01X227500Y96575D02*
X227591Y96484D01*
X229734D01*
X230325Y97075D01*
X233500D01*
G01X229000Y101000D02*
Y99500D01*
X227500Y98000D01*
Y96575D01*
G01X215294Y119951D02*
Y117094D01*
G01X223338Y119951D02*
X219313D01*
G01X231415D02*
X227370D01*
G01X219313D02*
X215294D01*
G01X227370D02*
X223338D01*
G01X212991Y169197D02*
X213062Y169126D01*
X215498D01*
G01X227061Y176428D02*
Y177137D01*
X225552Y178646D01*
G01X231111Y176403D02*
X227086D01*
X227061Y176428D01*
G01X215446Y216030D02*
X214492D01*
X212991Y217531D01*
Y219553D01*
G01X225363Y258525D02*
X225364Y258524D01*
Y258489D01*
X223800Y256925D01*
Y254800D01*
G01X223100Y252375D02*
Y254100D01*
X223800Y254800D01*
G01X229265Y258848D02*
X228865D01*
X228578Y259135D01*
X226010D01*
X225400Y258525D01*
X225363D01*
G01X214100Y258775D02*
X214950D01*
X216450Y260275D01*
Y262950D01*
X217500Y264000D01*
G01X227841Y275773D02*
X225441D01*
G01X226404Y293960D02*
X223646D01*
G01X217120Y293869D02*
X221154D01*
G01X212911D02*
X217120D01*
G01X223160Y362600D02*
X220027Y365733D01*
Y372129D01*
G01X224632Y369825D02*
X224565D01*
X223920Y370470D01*
Y373485D01*
G01D02*
X222636D01*
X221261Y374860D01*
X217975D01*
X216877Y373762D01*
Y372129D01*
G01X219050Y418850D02*
X218175Y419725D01*
X215800D01*
G01X227510Y57613D02*
X230800D01*
G01X227547Y79457D02*
Y74275D01*
G01X242047Y79457D02*
X239347D01*
G01X238188Y171773D02*
Y169235D01*
X238150Y169197D01*
G01X241200Y168475D02*
X238872D01*
X238150Y169197D01*
G01X230876Y180866D02*
Y180820D01*
X228702Y178646D01*
G01X232300Y261200D02*
Y259949D01*
X231199Y258848D01*
X229265D01*
G01X238420Y339155D02*
X235359D01*
X233468Y341046D01*
G01X236975Y374100D02*
Y373582D01*
X234893Y371500D01*
X233600D01*
G01X228230Y390390D02*
Y391907D01*
X230063Y393740D01*
G01X243250Y395825D02*
X240605D01*
X239750Y394970D01*
G01X252925Y54000D02*
Y51500D01*
G01X245175Y71900D02*
Y73575D01*
X246200Y74600D01*
G01X248000Y97075D02*
X247905D01*
X245391Y99589D01*
G01X252111Y110064D02*
X248087D01*
G01D02*
X246459D01*
X245200Y111323D01*
X244082D01*
G01X256333Y119951D02*
Y113408D01*
X256100Y113175D01*
G01X256333Y119951D02*
X258050D01*
X258550Y119451D01*
X260346D01*
G01X256671Y158751D02*
X256579Y158659D01*
Y156517D01*
X255492Y155430D01*
Y152905D01*
G01X244500Y206425D02*
Y203855D01*
X244450Y203805D01*
G01X257500Y273925D02*
X257230Y273655D01*
X253388D01*
G01X265922Y354238D02*
X259672D01*
X255600Y358310D01*
Y360806D01*
X255593Y360873D01*
X255588Y360887D01*
X253375Y363100D01*
G01Y351200D02*
X254150D01*
X259420Y345930D01*
G01X253375Y359100D02*
Y355200D01*
G01X271100Y346575D02*
X264296D01*
X255671Y355200D01*
X253375D01*
G01X250300Y370875D02*
X246196D01*
X245301Y369980D01*
X244000D01*
X243750Y369730D01*
G01X274219Y51641D02*
Y50219D01*
X273000Y49000D01*
X271575D01*
G01X277000Y75925D02*
X273324D01*
X271799Y74400D01*
X268675D01*
G01X268435Y121476D02*
Y117366D01*
G01X274007Y121400D02*
X271602D01*
G01X260346Y119451D02*
X262951D01*
X267060Y123560D01*
Y124750D01*
G01D02*
X270900D01*
X271200Y125050D01*
X273450D01*
G01X271470Y216354D02*
X271152D01*
X269391Y214593D01*
G01X270375Y384100D02*
X270100Y383825D01*
Y379900D01*
X274100Y375900D01*
X276100D01*
G01X262310Y384400D02*
X261168Y385542D01*
Y391007D01*
G01D02*
X262451Y392290D01*
X265320D01*
G01X269528Y466378D02*
Y459067D01*
X269534Y459061D01*
G01X285000Y75925D02*
X281000D01*
G01D02*
X277000D01*
G01X277157Y121400D02*
Y120177D01*
X278227Y119107D01*
Y117391D01*
G01X279200Y114100D02*
X278227Y115073D01*
Y117391D01*
G01X286549Y110768D02*
X283232D01*
X281700Y112300D01*
Y117068D01*
X281377Y117391D01*
G01D02*
Y121877D01*
X283500Y124000D01*
Y126000D01*
G01X285469Y165802D02*
X285980Y165291D01*
Y163487D01*
G01X282240Y197834D02*
X282395Y197989D01*
X286105D01*
G01X282907Y187033D02*
X284606D01*
X286105Y185534D01*
G01X282240Y194684D02*
X285950D01*
X286105Y194839D01*
G01X278089Y213530D02*
Y209511D01*
G01D02*
X278180Y209420D01*
Y207277D01*
X277600Y206697D01*
Y203401D01*
X279301Y201700D01*
X282192D01*
G01D02*
X285544D01*
X286105Y201139D01*
G01X281239Y209511D02*
X285030D01*
X286106Y210587D01*
G01X286611Y216534D02*
X288349D01*
X289254Y215629D01*
Y213737D01*
G01X281239Y213530D02*
X285914D01*
X286105Y213721D01*
G01X281889Y272347D02*
Y269899D01*
G01X285911Y272347D02*
Y269899D01*
G01Y285227D02*
X281889D01*
G01D02*
Y287636D01*
G01X300856Y104059D02*
X301825Y103090D01*
X309935D01*
G01X301936Y146297D02*
Y143897D01*
G01X301507Y181885D02*
Y185885D01*
G01Y193035D02*
Y195435D01*
G01Y189885D02*
X305507D01*
G01X301507Y185885D02*
Y189885D01*
G01X291012Y187914D02*
Y187292D01*
X289254Y185534D01*
G01X301426Y205854D02*
Y210150D01*
X303940Y212664D01*
G01X298276Y205854D02*
X296910D01*
X295410Y207354D01*
Y210587D01*
G01X294162Y365977D02*
X297502Y362637D01*
X308906D01*
G01X293289Y397365D02*
X297382D01*
X297399Y397382D01*
G01D02*
X302675D01*
G01X318000Y130175D02*
Y128000D01*
X315900Y125900D01*
G01X305936Y146297D02*
Y143897D01*
G01X309936Y146297D02*
Y143897D01*
G01X313936Y146297D02*
Y143897D01*
G01X317834Y169378D02*
X316168D01*
X314930Y168140D01*
G01X318855Y183411D02*
X317603D01*
X314930Y180738D01*
G01X316979Y192369D02*
X314986D01*
X314307Y191690D01*
G01X313459Y188372D02*
Y187835D01*
X311158Y185534D01*
G01X321602Y190495D02*
X319979D01*
X317850Y189613D01*
X316609Y188372D01*
G01D02*
Y187836D01*
X314307Y185534D01*
G01X305507Y193035D02*
X306204D01*
X308008Y194839D01*
G01X316979Y195519D02*
X314987D01*
X314307Y194839D01*
G01X317111Y208434D02*
X315303D01*
X314307Y207438D01*
G01X308755Y200789D02*
X310808D01*
X311158Y201139D01*
G01X321686Y207664D02*
X320048D01*
X317946Y205562D01*
X315581D01*
X314307Y204288D01*
G01X317111Y211584D02*
X315304D01*
X314307Y210587D01*
G01X311730Y216137D02*
Y214309D01*
X311158Y213737D01*
G01X314880Y216137D02*
Y214310D01*
X314307Y213737D01*
G01X314375Y260300D02*
Y268775D01*
G01X315075Y369000D02*
Y366500D01*
G01X312226Y386296D02*
Y382766D01*
G01X331881Y104577D02*
X331782Y104676D01*
X329463D01*
G01Y108692D02*
X331782D01*
X331881Y108593D01*
G01Y112608D02*
X331782Y112707D01*
X329463D01*
G01X328421Y150140D02*
X332289D01*
X333278Y151129D01*
G01X317936Y146297D02*
Y143897D01*
G01X323509Y153377D02*
X325271Y151615D01*
Y150140D01*
G01X329005Y155411D02*
Y152657D01*
G01X320984Y157378D02*
X323384D01*
G01X320984Y165378D02*
X323384D01*
G01X320984Y161378D02*
X323384D01*
G01X329005Y159411D02*
Y158911D01*
X330505Y157411D01*
X331405D01*
G01X321109Y153377D02*
X323509D01*
G01X329005Y163411D02*
Y167411D01*
G01X331405D02*
X333750D01*
X334250Y166911D01*
G01X329005Y167411D02*
X331405D01*
G01X320984Y169378D02*
X323384D01*
G01X320984Y173378D02*
X323384D01*
G01X320984Y177378D02*
X323384D01*
G01X329005Y179411D02*
Y178606D01*
X331049Y177329D01*
X331405Y177411D01*
G01X329005Y191411D02*
X330005Y192411D01*
X331405D01*
G01X329005Y187411D02*
X331405D01*
G01D02*
X333800D01*
X334250Y186961D01*
G01X317116Y202525D02*
X318216D01*
X319601Y201140D01*
G01X321686Y203664D02*
Y207664D01*
G01X330917Y390701D02*
Y386635D01*
G01D02*
Y383883D01*
X331500Y383300D01*
G01X337490Y104676D02*
X339809D01*
X339908Y104577D01*
G01X337490Y108692D02*
X339809D01*
X339908Y108593D01*
G01X337490Y112708D02*
X339809D01*
X339908Y112609D01*
G01X337400Y154911D02*
Y153921D01*
X339369Y151952D01*
G01X337400Y166911D02*
X338800D01*
X339800Y165911D01*
G01X337400Y162911D02*
X339939D01*
G01X337400Y158911D02*
Y162911D01*
G01Y178911D02*
Y182926D01*
G01X337328Y174911D02*
X338281D01*
X339812Y173380D01*
G01X337328Y170911D02*
Y174911D01*
G01X337400Y186961D02*
Y190961D01*
G01D02*
Y193449D01*
G01Y182926D02*
X339800D01*
G01X334067Y386635D02*
Y390701D01*
G01X334600Y383300D02*
Y384400D01*
X334067Y384933D01*
Y386635D01*
M02*
